FILE_TYPE = MACRO_DRAWING;
SET COLOR_WIRE YELLOW;
SET COLOR_PROP ORANGE;
SET COLOR_DOT WHITE;
SET COLOR_ARC YELLOW;
SET COLOR_BODY GREEN;
SET COLOR_NOTE PURPLE;
SET PROP_DISPLAY VALUE;
SET PAGE_NUMBER P44;
FORCEADD GENOA_SP5..8
(-4625 3525);
FORCEPROP 1 LAST LOCATION U26
J 0
(-5270 6356);
DISPLAY 0.489362 (-5270 6356);
PAINT SKYBLUE (-5270 6356);
FORCEPROP 0 LAST $SEC 8
J 0
(-5250 6400);
DISPLAY 0.680851 (-5250 6400);
PAINT MONO (-5250 6400);
DISPLAY INVISIBLE (-5250 6400);
FORCEPROP 0 LAST CDS_SEC 8
J 0
(-5275 6350);
DISPLAY 1.021277 (-5275 6350);
DISPLAY INVISIBLE (-5275 6350);
FORCEPROP 0 LASTPIN (-5425 2900) $PN BC12
J 2
(-5435 2910);
DISPLAY 0.489362 (-5435 2910);
PAINT MONO (-5435 2910);
FORCEPROP 0 LASTPIN (-5425 2850) $PN BD13
J 2
(-5435 2860);
DISPLAY 0.489362 (-5435 2860);
PAINT MONO (-5435 2860);
FORCEPROP 0 LASTPIN (-5425 1750) $PN BF13
J 2
(-5435 1760);
DISPLAY 0.489362 (-5435 1760);
PAINT MONO (-5435 1760);
FORCEPROP 0 LASTPIN (-5425 1700) $PN BG12
J 2
(-5435 1710);
DISPLAY 0.489362 (-5435 1710);
PAINT MONO (-5435 1710);
FORCEPROP 0 LASTPIN (-5425 2050) $PN AT14
J 2
(-5435 2060);
DISPLAY 0.489362 (-5435 2060);
PAINT MONO (-5435 2060);
FORCEPROP 0 LASTPIN (-5425 1950) $PN AU14
J 2
(-5435 1960);
DISPLAY 0.489362 (-5435 1960);
PAINT MONO (-5435 1960);
FORCEPROP 0 LASTPIN (-5425 2750) $PN AU12
J 2
(-5435 2760);
DISPLAY 0.489362 (-5435 2760);
PAINT MONO (-5435 2760);
FORCEPROP 0 LASTPIN (-5425 2700) $PN AV14
J 2
(-5435 2710);
DISPLAY 0.489362 (-5435 2710);
PAINT MONO (-5435 2710);
FORCEPROP 0 LASTPIN (-5425 2600) $PN BN14
J 2
(-5435 2610);
DISPLAY 0.489362 (-5435 2610);
PAINT MONO (-5435 2610);
FORCEPROP 0 LASTPIN (-5425 1600) $PN AV13
J 2
(-5435 1610);
DISPLAY 0.489362 (-5435 1610);
PAINT MONO (-5435 1610);
FORCEPROP 0 LASTPIN (-5425 1550) $PN AW14
J 2
(-5435 1560);
DISPLAY 0.489362 (-5435 1560);
PAINT MONO (-5435 1560);
FORCEPROP 0 LASTPIN (-5425 1450) $PN BP14
J 2
(-5435 1460);
DISPLAY 0.489362 (-5435 1460);
PAINT MONO (-5435 1460);
FORCEPROP 0 LASTPIN (-5425 3750) $PN AW12
J 2
(-5435 3760);
DISPLAY 0.489362 (-5435 3760);
PAINT MONO (-5435 3760);
FORCEPROP 0 LASTPIN (-5425 3700) $PN AY13
J 2
(-5435 3710);
DISPLAY 0.489362 (-5435 3710);
PAINT MONO (-5435 3710);
FORCEPROP 0 LASTPIN (-5425 3650) $PN AY14
J 2
(-5435 3660);
DISPLAY 0.489362 (-5435 3660);
PAINT MONO (-5435 3660);
FORCEPROP 0 LASTPIN (-5425 3600) $PN BA14
J 2
(-5435 3610);
DISPLAY 0.489362 (-5435 3610);
PAINT MONO (-5435 3610);
FORCEPROP 0 LASTPIN (-5425 3550) $PN BA12
J 2
(-5435 3560);
DISPLAY 0.489362 (-5435 3560);
PAINT MONO (-5435 3560);
FORCEPROP 0 LASTPIN (-5425 3500) $PN BB13
J 2
(-5435 3510);
DISPLAY 0.489362 (-5435 3510);
PAINT MONO (-5435 3510);
FORCEPROP 0 LASTPIN (-5425 3450) $PN BB14
J 2
(-5435 3460);
DISPLAY 0.489362 (-5435 3460);
PAINT MONO (-5435 3460);
FORCEPROP 0 LASTPIN (-3825 2300) $PN AJ12
J 0
(-3815 2310);
DISPLAY 0.489362 (-3815 2310);
PAINT MONO (-3815 2310);
FORCEPROP 0 LASTPIN (-3825 2250) $PN AK14
J 0
(-3815 2260);
DISPLAY 0.489362 (-3815 2260);
PAINT MONO (-3815 2260);
FORCEPROP 0 LASTPIN (-3825 2200) $PN AK13
J 0
(-3815 2210);
DISPLAY 0.489362 (-3815 2210);
PAINT MONO (-3815 2210);
FORCEPROP 0 LASTPIN (-3825 2150) $PN AL14
J 0
(-3815 2160);
DISPLAY 0.489362 (-3815 2160);
PAINT MONO (-3815 2160);
FORCEPROP 0 LASTPIN (-3825 2100) $PN AN12
J 0
(-3815 2110);
DISPLAY 0.489362 (-3815 2110);
PAINT MONO (-3815 2110);
FORCEPROP 0 LASTPIN (-3825 2050) $PN AP14
J 0
(-3815 2060);
DISPLAY 0.489362 (-3815 2060);
PAINT MONO (-3815 2060);
FORCEPROP 0 LASTPIN (-3825 2000) $PN AP13
J 0
(-3815 2010);
DISPLAY 0.489362 (-3815 2010);
PAINT MONO (-3815 2010);
FORCEPROP 0 LASTPIN (-3825 1950) $PN AR14
J 0
(-3815 1960);
DISPLAY 0.489362 (-3815 1960);
PAINT MONO (-3815 1960);
FORCEPROP 0 LASTPIN (-3825 5900) $PN E12
J 0
(-3815 5910);
DISPLAY 0.489362 (-3815 5910);
PAINT MONO (-3815 5910);
FORCEPROP 0 LASTPIN (-3825 5850) $PN F14
J 0
(-3815 5860);
DISPLAY 0.489362 (-3815 5860);
PAINT MONO (-3815 5860);
FORCEPROP 0 LASTPIN (-3825 5800) $PN F13
J 0
(-3815 5810);
DISPLAY 0.489362 (-3815 5810);
PAINT MONO (-3815 5810);
FORCEPROP 0 LASTPIN (-3825 5750) $PN G14
J 0
(-3815 5760);
DISPLAY 0.489362 (-3815 5760);
PAINT MONO (-3815 5760);
FORCEPROP 0 LASTPIN (-3825 5700) $PN J12
J 0
(-3815 5710);
DISPLAY 0.489362 (-3815 5710);
PAINT MONO (-3815 5710);
FORCEPROP 0 LASTPIN (-3825 5650) $PN K14
J 0
(-3815 5660);
DISPLAY 0.489362 (-3815 5660);
PAINT MONO (-3815 5660);
FORCEPROP 0 LASTPIN (-3825 5600) $PN K13
J 0
(-3815 5610);
DISPLAY 0.489362 (-3815 5610);
PAINT MONO (-3815 5610);
FORCEPROP 0 LASTPIN (-3825 5550) $PN L14
J 0
(-3815 5560);
DISPLAY 0.489362 (-3815 5560);
PAINT MONO (-3815 5560);
FORCEPROP 0 LASTPIN (-3825 5450) $PN L12
J 0
(-3815 5460);
DISPLAY 0.489362 (-3815 5460);
PAINT MONO (-3815 5460);
FORCEPROP 0 LASTPIN (-3825 5400) $PN M14
J 0
(-3815 5410);
DISPLAY 0.489362 (-3815 5410);
PAINT MONO (-3815 5410);
FORCEPROP 0 LASTPIN (-3825 5350) $PN M13
J 0
(-3815 5360);
DISPLAY 0.489362 (-3815 5360);
PAINT MONO (-3815 5360);
FORCEPROP 0 LASTPIN (-3825 5300) $PN N14
J 0
(-3815 5310);
DISPLAY 0.489362 (-3815 5310);
PAINT MONO (-3815 5310);
FORCEPROP 0 LASTPIN (-3825 5250) $PN R12
J 0
(-3815 5260);
DISPLAY 0.489362 (-3815 5260);
PAINT MONO (-3815 5260);
FORCEPROP 0 LASTPIN (-3825 5200) $PN T14
J 0
(-3815 5210);
DISPLAY 0.489362 (-3815 5210);
PAINT MONO (-3815 5210);
FORCEPROP 0 LASTPIN (-3825 5150) $PN T13
J 0
(-3815 5160);
DISPLAY 0.489362 (-3815 5160);
PAINT MONO (-3815 5160);
FORCEPROP 0 LASTPIN (-3825 5100) $PN U14
J 0
(-3815 5110);
DISPLAY 0.489362 (-3815 5110);
PAINT MONO (-3815 5110);
FORCEPROP 0 LASTPIN (-3825 5000) $PN U12
J 0
(-3815 5010);
DISPLAY 0.489362 (-3815 5010);
PAINT MONO (-3815 5010);
FORCEPROP 0 LASTPIN (-3825 4950) $PN V14
J 0
(-3815 4960);
DISPLAY 0.489362 (-3815 4960);
PAINT MONO (-3815 4960);
FORCEPROP 0 LASTPIN (-3825 4900) $PN V13
J 0
(-3815 4910);
DISPLAY 0.489362 (-3815 4910);
PAINT MONO (-3815 4910);
FORCEPROP 0 LASTPIN (-3825 4850) $PN W14
J 0
(-3815 4860);
DISPLAY 0.489362 (-3815 4860);
PAINT MONO (-3815 4860);
FORCEPROP 0 LASTPIN (-3825 4800) $PN AA12
J 0
(-3815 4810);
DISPLAY 0.489362 (-3815 4810);
PAINT MONO (-3815 4810);
FORCEPROP 0 LASTPIN (-3825 4750) $PN AB14
J 0
(-3815 4760);
DISPLAY 0.489362 (-3815 4760);
PAINT MONO (-3815 4760);
FORCEPROP 0 LASTPIN (-3825 4700) $PN AB13
J 0
(-3815 4710);
DISPLAY 0.489362 (-3815 4710);
PAINT MONO (-3815 4710);
FORCEPROP 0 LASTPIN (-3825 4650) $PN AC14
J 0
(-3815 4660);
DISPLAY 0.489362 (-3815 4660);
PAINT MONO (-3815 4660);
FORCEPROP 0 LASTPIN (-3825 4550) $PN AC12
J 0
(-3815 4560);
DISPLAY 0.489362 (-3815 4560);
PAINT MONO (-3815 4560);
FORCEPROP 0 LASTPIN (-3825 4500) $PN AD14
J 0
(-3815 4510);
DISPLAY 0.489362 (-3815 4510);
PAINT MONO (-3815 4510);
FORCEPROP 0 LASTPIN (-3825 4450) $PN AD13
J 0
(-3815 4460);
DISPLAY 0.489362 (-3815 4460);
PAINT MONO (-3815 4460);
FORCEPROP 0 LASTPIN (-3825 4400) $PN AE14
J 0
(-3815 4410);
DISPLAY 0.489362 (-3815 4410);
PAINT MONO (-3815 4410);
FORCEPROP 0 LASTPIN (-3825 4350) $PN AG12
J 0
(-3815 4360);
DISPLAY 0.489362 (-3815 4360);
PAINT MONO (-3815 4360);
FORCEPROP 0 LASTPIN (-3825 4300) $PN AH14
J 0
(-3815 4310);
DISPLAY 0.489362 (-3815 4310);
PAINT MONO (-3815 4310);
FORCEPROP 0 LASTPIN (-3825 4250) $PN AH13
J 0
(-3815 4260);
DISPLAY 0.489362 (-3815 4260);
PAINT MONO (-3815 4260);
FORCEPROP 0 LASTPIN (-3825 4200) $PN AJ14
J 0
(-3815 4210);
DISPLAY 0.489362 (-3815 4210);
PAINT MONO (-3815 4210);
FORCEPROP 0 LASTPIN (-5425 5900) $PN G12
J 2
(-5435 5910);
DISPLAY 0.489362 (-5435 5910);
PAINT MONO (-5435 5910);
FORCEPROP 0 LASTPIN (-5425 5800) $PN N12
J 2
(-5435 5810);
DISPLAY 0.489362 (-5435 5810);
PAINT MONO (-5435 5810);
FORCEPROP 0 LASTPIN (-5425 5700) $PN W12
J 2
(-5435 5710);
DISPLAY 0.489362 (-5435 5710);
PAINT MONO (-5435 5710);
FORCEPROP 0 LASTPIN (-5425 5600) $PN AE12
J 2
(-5435 5610);
DISPLAY 0.489362 (-5435 5610);
PAINT MONO (-5435 5610);
FORCEPROP 0 LASTPIN (-5425 5500) $PN AL12
J 2
(-5435 5510);
DISPLAY 0.489362 (-5435 5510);
PAINT MONO (-5435 5510);
FORCEPROP 0 LASTPIN (-5425 5400) $PN J14
J 2
(-5435 5410);
DISPLAY 0.489362 (-5435 5410);
PAINT MONO (-5435 5410);
FORCEPROP 0 LASTPIN (-5425 5300) $PN R14
J 2
(-5435 5310);
DISPLAY 0.489362 (-5435 5310);
PAINT MONO (-5435 5310);
FORCEPROP 0 LASTPIN (-5425 5200) $PN AA14
J 2
(-5435 5210);
DISPLAY 0.489362 (-5435 5210);
PAINT MONO (-5435 5210);
FORCEPROP 0 LASTPIN (-5425 5100) $PN AG14
J 2
(-5435 5110);
DISPLAY 0.489362 (-5435 5110);
PAINT MONO (-5435 5110);
FORCEPROP 0 LASTPIN (-5425 5000) $PN AN14
J 2
(-5435 5010);
DISPLAY 0.489362 (-5435 5010);
PAINT MONO (-5435 5010);
FORCEPROP 0 LASTPIN (-5425 5850) $PN H13
J 2
(-5435 5860);
DISPLAY 0.489362 (-5435 5860);
PAINT MONO (-5435 5860);
FORCEPROP 0 LASTPIN (-5425 5750) $PN P13
J 2
(-5435 5760);
DISPLAY 0.489362 (-5435 5760);
PAINT MONO (-5435 5760);
FORCEPROP 0 LASTPIN (-5425 5650) $PN Y13
J 2
(-5435 5660);
DISPLAY 0.489362 (-5435 5660);
PAINT MONO (-5435 5660);
FORCEPROP 0 LASTPIN (-5425 5550) $PN AF13
J 2
(-5435 5560);
DISPLAY 0.489362 (-5435 5560);
PAINT MONO (-5435 5560);
FORCEPROP 0 LASTPIN (-5425 5450) $PN AM13
J 2
(-5435 5460);
DISPLAY 0.489362 (-5435 5460);
PAINT MONO (-5435 5460);
FORCEPROP 0 LASTPIN (-5425 5350) $PN H14
J 2
(-5435 5360);
DISPLAY 0.489362 (-5435 5360);
PAINT MONO (-5435 5360);
FORCEPROP 0 LASTPIN (-5425 5250) $PN P14
J 2
(-5435 5260);
DISPLAY 0.489362 (-5435 5260);
PAINT MONO (-5435 5260);
FORCEPROP 0 LASTPIN (-5425 5150) $PN Y14
J 2
(-5435 5160);
DISPLAY 0.489362 (-5435 5160);
PAINT MONO (-5435 5160);
FORCEPROP 0 LASTPIN (-5425 5050) $PN AF14
J 2
(-5435 5060);
DISPLAY 0.489362 (-5435 5060);
PAINT MONO (-5435 5060);
FORCEPROP 0 LASTPIN (-5425 4950) $PN AM14
J 2
(-5435 4960);
DISPLAY 0.489362 (-5435 4960);
PAINT MONO (-5435 4960);
FORCEPROP 0 LASTPIN (-5425 2500) $PN BC14
J 2
(-5435 2510);
DISPLAY 0.489362 (-5435 2510);
PAINT MONO (-5435 2510);
FORCEPROP 0 LASTPIN (-5425 2400) $PN BM14
J 2
(-5435 2410);
DISPLAY 0.489362 (-5435 2410);
PAINT MONO (-5435 2410);
FORCEPROP 0 LASTPIN (-5425 2350) $PN BN12
J 2
(-5435 2360);
DISPLAY 0.489362 (-5435 2360);
PAINT MONO (-5435 2360);
FORCEPROP 0 LASTPIN (-5425 2250) $PN BP13
J 2
(-5435 2260);
DISPLAY 0.489362 (-5435 2260);
PAINT MONO (-5435 2260);
FORCEPROP 0 LASTPIN (-5425 1350) $PN BL12
J 2
(-5435 1360);
DISPLAY 0.489362 (-5435 1360);
PAINT MONO (-5435 1360);
FORCEPROP 0 LASTPIN (-5425 1300) $PN BM13
J 2
(-5435 1310);
DISPLAY 0.489362 (-5435 1310);
PAINT MONO (-5435 1310);
FORCEPROP 0 LASTPIN (-5425 1200) $PN BR12
J 2
(-5435 1210);
DISPLAY 0.489362 (-5435 1210);
PAINT MONO (-5435 1210);
FORCEPROP 0 LASTPIN (-5425 3350) $PN BG14
J 2
(-5435 3360);
DISPLAY 0.489362 (-5435 3360);
PAINT MONO (-5435 3360);
FORCEPROP 0 LASTPIN (-5425 3300) $PN BH14
J 2
(-5435 3310);
DISPLAY 0.489362 (-5435 3310);
PAINT MONO (-5435 3310);
FORCEPROP 0 LASTPIN (-5425 3250) $PN BH13
J 2
(-5435 3260);
DISPLAY 0.489362 (-5435 3260);
PAINT MONO (-5435 3260);
FORCEPROP 0 LASTPIN (-5425 3200) $PN BJ12
J 2
(-5435 3210);
DISPLAY 0.489362 (-5435 3210);
PAINT MONO (-5435 3210);
FORCEPROP 0 LASTPIN (-5425 3150) $PN BJ14
J 2
(-5435 3160);
DISPLAY 0.489362 (-5435 3160);
PAINT MONO (-5435 3160);
FORCEPROP 0 LASTPIN (-5425 3100) $PN BK14
J 2
(-5435 3110);
DISPLAY 0.489362 (-5435 3110);
PAINT MONO (-5435 3110);
FORCEPROP 0 LASTPIN (-5425 3050) $PN BK13
J 2
(-5435 3060);
DISPLAY 0.489362 (-5435 3060);
PAINT MONO (-5435 3060);
FORCEPROP 0 LASTPIN (-3825 1850) $PN BY13
J 0
(-3815 1860);
DISPLAY 0.489362 (-3815 1860);
PAINT MONO (-3815 1860);
FORCEPROP 0 LASTPIN (-3825 1800) $PN CA14
J 0
(-3815 1810);
DISPLAY 0.489362 (-3815 1810);
PAINT MONO (-3815 1810);
FORCEPROP 0 LASTPIN (-3825 1750) $PN CA12
J 0
(-3815 1760);
DISPLAY 0.489362 (-3815 1760);
PAINT MONO (-3815 1760);
FORCEPROP 0 LASTPIN (-3825 1700) $PN CB14
J 0
(-3815 1710);
DISPLAY 0.489362 (-3815 1710);
PAINT MONO (-3815 1710);
FORCEPROP 0 LASTPIN (-3825 1650) $PN BT13
J 0
(-3815 1660);
DISPLAY 0.489362 (-3815 1660);
PAINT MONO (-3815 1660);
FORCEPROP 0 LASTPIN (-3825 1600) $PN BU14
J 0
(-3815 1610);
DISPLAY 0.489362 (-3815 1610);
PAINT MONO (-3815 1610);
FORCEPROP 0 LASTPIN (-3825 1550) $PN BU12
J 0
(-3815 1560);
DISPLAY 0.489362 (-3815 1560);
PAINT MONO (-3815 1560);
FORCEPROP 0 LASTPIN (-3825 1500) $PN BV14
J 0
(-3815 1510);
DISPLAY 0.489362 (-3815 1510);
PAINT MONO (-3815 1510);
FORCEPROP 0 LASTPIN (-3825 4100) $PN CB13
J 0
(-3815 4110);
DISPLAY 0.489362 (-3815 4110);
PAINT MONO (-3815 4110);
FORCEPROP 0 LASTPIN (-3825 4050) $PN CC14
J 0
(-3815 4060);
DISPLAY 0.489362 (-3815 4060);
PAINT MONO (-3815 4060);
FORCEPROP 0 LASTPIN (-3825 4000) $PN CC12
J 0
(-3815 4010);
DISPLAY 0.489362 (-3815 4010);
PAINT MONO (-3815 4010);
FORCEPROP 0 LASTPIN (-3825 3950) $PN CD14
J 0
(-3815 3960);
DISPLAY 0.489362 (-3815 3960);
PAINT MONO (-3815 3960);
FORCEPROP 0 LASTPIN (-3825 3900) $PN CF13
J 0
(-3815 3910);
DISPLAY 0.489362 (-3815 3910);
PAINT MONO (-3815 3910);
FORCEPROP 0 LASTPIN (-3825 3850) $PN CG14
J 0
(-3815 3860);
DISPLAY 0.489362 (-3815 3860);
PAINT MONO (-3815 3860);
FORCEPROP 0 LASTPIN (-3825 3800) $PN CG12
J 0
(-3815 3810);
DISPLAY 0.489362 (-3815 3810);
PAINT MONO (-3815 3810);
FORCEPROP 0 LASTPIN (-3825 3750) $PN CH14
J 0
(-3815 3760);
DISPLAY 0.489362 (-3815 3760);
PAINT MONO (-3815 3760);
FORCEPROP 0 LASTPIN (-3825 3650) $PN CH13
J 0
(-3815 3660);
DISPLAY 0.489362 (-3815 3660);
PAINT MONO (-3815 3660);
FORCEPROP 0 LASTPIN (-3825 3600) $PN CJ14
J 0
(-3815 3610);
DISPLAY 0.489362 (-3815 3610);
PAINT MONO (-3815 3610);
FORCEPROP 0 LASTPIN (-3825 3550) $PN CJ12
J 0
(-3815 3560);
DISPLAY 0.489362 (-3815 3560);
PAINT MONO (-3815 3560);
FORCEPROP 0 LASTPIN (-3825 3500) $PN CK14
J 0
(-3815 3510);
DISPLAY 0.489362 (-3815 3510);
PAINT MONO (-3815 3510);
FORCEPROP 0 LASTPIN (-3825 3450) $PN CM13
J 0
(-3815 3460);
DISPLAY 0.489362 (-3815 3460);
PAINT MONO (-3815 3460);
FORCEPROP 0 LASTPIN (-3825 3400) $PN CN14
J 0
(-3815 3410);
DISPLAY 0.489362 (-3815 3410);
PAINT MONO (-3815 3410);
FORCEPROP 0 LASTPIN (-3825 3350) $PN CN12
J 0
(-3815 3360);
DISPLAY 0.489362 (-3815 3360);
PAINT MONO (-3815 3360);
FORCEPROP 0 LASTPIN (-3825 3300) $PN CP14
J 0
(-3815 3310);
DISPLAY 0.489362 (-3815 3310);
PAINT MONO (-3815 3310);
FORCEPROP 0 LASTPIN (-3825 3200) $PN CP13
J 0
(-3815 3210);
DISPLAY 0.489362 (-3815 3210);
PAINT MONO (-3815 3210);
FORCEPROP 0 LASTPIN (-3825 3150) $PN CR14
J 0
(-3815 3160);
DISPLAY 0.489362 (-3815 3160);
PAINT MONO (-3815 3160);
FORCEPROP 0 LASTPIN (-3825 3100) $PN CR12
J 0
(-3815 3110);
DISPLAY 0.489362 (-3815 3110);
PAINT MONO (-3815 3110);
FORCEPROP 0 LASTPIN (-3825 3050) $PN CT14
J 0
(-3815 3060);
DISPLAY 0.489362 (-3815 3060);
PAINT MONO (-3815 3060);
FORCEPROP 0 LASTPIN (-3825 3000) $PN CV13
J 0
(-3815 3010);
DISPLAY 0.489362 (-3815 3010);
PAINT MONO (-3815 3010);
FORCEPROP 0 LASTPIN (-3825 2950) $PN CW14
J 0
(-3815 2960);
DISPLAY 0.489362 (-3815 2960);
PAINT MONO (-3815 2960);
FORCEPROP 0 LASTPIN (-3825 2900) $PN CW12
J 0
(-3815 2910);
DISPLAY 0.489362 (-3815 2910);
PAINT MONO (-3815 2910);
FORCEPROP 0 LASTPIN (-3825 2850) $PN CY14
J 0
(-3815 2860);
DISPLAY 0.489362 (-3815 2860);
PAINT MONO (-3815 2860);
FORCEPROP 0 LASTPIN (-3825 2750) $PN CY13
J 0
(-3815 2760);
DISPLAY 0.489362 (-3815 2760);
PAINT MONO (-3815 2760);
FORCEPROP 0 LASTPIN (-3825 2700) $PN DA14
J 0
(-3815 2710);
DISPLAY 0.489362 (-3815 2710);
PAINT MONO (-3815 2710);
FORCEPROP 0 LASTPIN (-3825 2650) $PN DA12
J 0
(-3815 2660);
DISPLAY 0.489362 (-3815 2660);
PAINT MONO (-3815 2660);
FORCEPROP 0 LASTPIN (-3825 2600) $PN DB14
J 0
(-3815 2610);
DISPLAY 0.489362 (-3815 2610);
PAINT MONO (-3815 2610);
FORCEPROP 0 LASTPIN (-3825 2550) $PN DD13
J 0
(-3815 2560);
DISPLAY 0.489362 (-3815 2560);
PAINT MONO (-3815 2560);
FORCEPROP 0 LASTPIN (-3825 2500) $PN DE14
J 0
(-3815 2510);
DISPLAY 0.489362 (-3815 2510);
PAINT MONO (-3815 2510);
FORCEPROP 0 LASTPIN (-3825 2450) $PN DE12
J 0
(-3815 2460);
DISPLAY 0.489362 (-3815 2460);
PAINT MONO (-3815 2460);
FORCEPROP 0 LASTPIN (-3825 2400) $PN DF14
J 0
(-3815 2410);
DISPLAY 0.489362 (-3815 2410);
PAINT MONO (-3815 2410);
FORCEPROP 0 LASTPIN (-5425 4850) $PN CD13
J 2
(-5435 4860);
DISPLAY 0.489362 (-5435 4860);
PAINT MONO (-5435 4860);
FORCEPROP 0 LASTPIN (-5425 4750) $PN CK13
J 2
(-5435 4760);
DISPLAY 0.489362 (-5435 4760);
PAINT MONO (-5435 4760);
FORCEPROP 0 LASTPIN (-5425 4650) $PN CT13
J 2
(-5435 4660);
DISPLAY 0.489362 (-5435 4660);
PAINT MONO (-5435 4660);
FORCEPROP 0 LASTPIN (-5425 4550) $PN DB13
J 2
(-5435 4560);
DISPLAY 0.489362 (-5435 4560);
PAINT MONO (-5435 4560);
FORCEPROP 0 LASTPIN (-5425 4450) $PN BY14
J 2
(-5435 4460);
DISPLAY 0.489362 (-5435 4460);
PAINT MONO (-5435 4460);
FORCEPROP 0 LASTPIN (-5425 4350) $PN CF14
J 2
(-5435 4360);
DISPLAY 0.489362 (-5435 4360);
PAINT MONO (-5435 4360);
FORCEPROP 0 LASTPIN (-5425 4250) $PN CM14
J 2
(-5435 4260);
DISPLAY 0.489362 (-5435 4260);
PAINT MONO (-5435 4260);
FORCEPROP 0 LASTPIN (-5425 4150) $PN CV14
J 2
(-5435 4160);
DISPLAY 0.489362 (-5435 4160);
PAINT MONO (-5435 4160);
FORCEPROP 0 LASTPIN (-5425 4050) $PN DD14
J 2
(-5435 4060);
DISPLAY 0.489362 (-5435 4060);
PAINT MONO (-5435 4060);
FORCEPROP 0 LASTPIN (-5425 3950) $PN BV13
J 2
(-5435 3960);
DISPLAY 0.489362 (-5435 3960);
PAINT MONO (-5435 3960);
FORCEPROP 0 LASTPIN (-5425 4800) $PN CE12
J 2
(-5435 4810);
DISPLAY 0.489362 (-5435 4810);
PAINT MONO (-5435 4810);
FORCEPROP 0 LASTPIN (-5425 4700) $PN CL12
J 2
(-5435 4710);
DISPLAY 0.489362 (-5435 4710);
PAINT MONO (-5435 4710);
FORCEPROP 0 LASTPIN (-5425 4600) $PN CU12
J 2
(-5435 4610);
DISPLAY 0.489362 (-5435 4610);
PAINT MONO (-5435 4610);
FORCEPROP 0 LASTPIN (-5425 4500) $PN DC12
J 2
(-5435 4510);
DISPLAY 0.489362 (-5435 4510);
PAINT MONO (-5435 4510);
FORCEPROP 0 LASTPIN (-5425 4400) $PN BW14
J 2
(-5435 4410);
DISPLAY 0.489362 (-5435 4410);
PAINT MONO (-5435 4410);
FORCEPROP 0 LASTPIN (-5425 4300) $PN CE14
J 2
(-5435 4310);
DISPLAY 0.489362 (-5435 4310);
PAINT MONO (-5435 4310);
FORCEPROP 0 LASTPIN (-5425 4200) $PN CL14
J 2
(-5435 4210);
DISPLAY 0.489362 (-5435 4210);
PAINT MONO (-5435 4210);
FORCEPROP 0 LASTPIN (-5425 4100) $PN CU14
J 2
(-5435 4110);
DISPLAY 0.489362 (-5435 4110);
PAINT MONO (-5435 4110);
FORCEPROP 0 LASTPIN (-5425 4000) $PN DC14
J 2
(-5435 4010);
DISPLAY 0.489362 (-5435 4010);
PAINT MONO (-5435 4010);
FORCEPROP 0 LASTPIN (-5425 3900) $PN BW12
J 2
(-5435 3910);
DISPLAY 0.489362 (-5435 3910);
PAINT MONO (-5435 3910);
FORCEPROP 0 LASTPIN (-5425 2150) $PN BL14
J 2
(-5435 2160);
DISPLAY 0.489362 (-5435 2160);
PAINT MONO (-5435 2160);
FORCEPROP 0 LASTPIN (-5425 1100) $PN BF14
J 2
(-5435 1110);
DISPLAY 0.489362 (-5435 1110);
PAINT MONO (-5435 1110);
FORCEPROP 2 LAST PART_TYPE SMLF
J 0
(-5275 6300);
DISPLAY 1.021277 (-5275 6300);
FORCEPROP 1 LAST MATERIAL IO
J 0
(-5270 6082);
DISPLAY 0.489362 (-5270 6082);
PAINT SKYBLUE (-5270 6082);
FORCEPROP 2 LAST VALUE SOCKET6096_13568-001
J 0
(-5275 6200);
DISPLAY 0.489362 (-5275 6200);
PAINT SKYBLUE (-5275 6200);
FORCEPROP 1 LAST PART_NUMBER DGA^6000030
J 0
(-5270 6209);
DISPLAY 0.489362 (-5270 6209);
PAINT SKYBLUE (-5270 6209);
FORCEPROP 2 LAST CDS_LIB pure_quanta
J 0
(-4625 3525);
DISPLAY INVISIBLE (-4625 3525);
FORCEPROP 1 LAST CDS_LMAN_SYM_OUTLINE -650,2525,650,-2525
J 0
(-4625 3525);
DISPLAY 0.468085 (-4625 3525);
PAINT GREEN (-4625 3525);
DISPLAY INVISIBLE (-4625 3525);
FORCEPROP 1 LAST NEEDS_NO_SIZE TRUE
J 0
(-4625 3525);
DISPLAY 0.723404 (-4625 3525);
PAINT GREEN (-4625 3525);
DISPLAY INVISIBLE (-4625 3525);
FORCEPROP 1 LAST PATH I159
J 0
(-4625 3525);
DISPLAY 0.723404 (-4625 3525);
PAINT GREEN (-4625 3525);
DISPLAY INVISIBLE (-4625 3525);
FORCEADD OFFPAGE..3
(-2625 5925);
FORCEPROP 2 LAST $XR0 104 
J 0
(-2411 5925);
DISPLAY 0.638298 (-2411 5925);
PAINT MONO (-2411 5925);
FORCEPROP 2 LAST PATH I160
J 0
(-2400 5975);
DISPLAY 1.021277 (-2400 5975);
DISPLAY INVISIBLE (-2400 5975);
FORCEPROP 1 LAST COMMENT_BODY TRUE
J 0
(-2675 5825);
DISPLAY 0.872340 (-2675 5825);
PAINT GREEN (-2675 5825);
DISPLAY INVISIBLE (-2675 5825);
FORCEPROP 1 LAST OFFPAGE TRUE
J 0
(-2300 5800);
DISPLAY 0.872340 (-2300 5800);
PAINT GREEN (-2300 5800);
DISPLAY INVISIBLE (-2300 5800);
FORCEPROP 2 LAST CDS_LIB mstr_standard
J 0
(-2625 5925);
DISPLAY 0.723404 (-2625 5925);
PAINT MONO (-2625 5925);
DISPLAY INVISIBLE (-2625 5925);
FORCEADD TAP..1
(-3350 5900);
FORCEPROP 3 LASTPIN (-3400 5900) SIG_NAME M_H_CPU1_SA_DQ<0>
J 0
(-3390 5910);
DISPLAY 0.659574 (-3390 5910);
PAINT MONO (-3390 5910);
DISPLAY INVISIBLE (-3390 5910);
FORCEPROP 1 LASTPIN (-3400 5900) BN 0
J 0
(-3412 5908);
DISPLAY 0.489362 (-3412 5908);
PAINT GREEN (-3412 5908);
FORCEPROP 2 LAST CDS_LIB mstr_standard
J 0
(-3350 5900);
DISPLAY 0.723404 (-3350 5900);
PAINT MONO (-3350 5900);
DISPLAY INVISIBLE (-3350 5900);
FORCEPROP 1 LAST BODY_TYPE PLUMBING
J 0
(-3350 5950);
DISPLAY 0.872340 (-3350 5950);
PAINT GREEN (-3350 5950);
DISPLAY INVISIBLE (-3350 5950);
FORCEPROP 1 LAST HDL_TAP TRUE
J 0
(-3025 5775);
DISPLAY 0.872340 (-3025 5775);
DISPLAY INVISIBLE (-3025 5775);
FORCEPROP 1 LAST PATH I161
J 0
(-3352 5900);
DISPLAY 0.872340 (-3352 5900);
PAINT GREEN (-3352 5900);
DISPLAY INVISIBLE (-3352 5900);
FORCEADD TAP..1
(-3350 5800);
FORCEPROP 3 LASTPIN (-3400 5800) SIG_NAME M_H_CPU1_SA_DQ<2>
J 0
(-3390 5810);
DISPLAY 0.659574 (-3390 5810);
PAINT MONO (-3390 5810);
DISPLAY INVISIBLE (-3390 5810);
FORCEPROP 1 LASTPIN (-3400 5800) BN 2
J 0
(-3412 5808);
DISPLAY 0.489362 (-3412 5808);
PAINT GREEN (-3412 5808);
FORCEPROP 2 LAST CDS_LIB mstr_standard
J 0
(-3350 5800);
DISPLAY 0.723404 (-3350 5800);
PAINT MONO (-3350 5800);
DISPLAY INVISIBLE (-3350 5800);
FORCEPROP 1 LAST BODY_TYPE PLUMBING
J 0
(-3350 5850);
DISPLAY 0.872340 (-3350 5850);
PAINT GREEN (-3350 5850);
DISPLAY INVISIBLE (-3350 5850);
FORCEPROP 1 LAST HDL_TAP TRUE
J 0
(-3025 5675);
DISPLAY 0.872340 (-3025 5675);
DISPLAY INVISIBLE (-3025 5675);
FORCEPROP 1 LAST PATH I162
J 0
(-3352 5800);
DISPLAY 0.872340 (-3352 5800);
PAINT GREEN (-3352 5800);
DISPLAY INVISIBLE (-3352 5800);
FORCEADD TAP..1
(-3350 5850);
FORCEPROP 3 LASTPIN (-3400 5850) SIG_NAME M_H_CPU1_SA_DQ<1>
J 0
(-3390 5860);
DISPLAY 0.659574 (-3390 5860);
PAINT MONO (-3390 5860);
DISPLAY INVISIBLE (-3390 5860);
FORCEPROP 1 LASTPIN (-3400 5850) BN 1
J 0
(-3412 5858);
DISPLAY 0.489362 (-3412 5858);
PAINT GREEN (-3412 5858);
FORCEPROP 2 LAST CDS_LIB mstr_standard
J 0
(-3350 5850);
DISPLAY 0.723404 (-3350 5850);
PAINT MONO (-3350 5850);
DISPLAY INVISIBLE (-3350 5850);
FORCEPROP 1 LAST BODY_TYPE PLUMBING
J 0
(-3350 5900);
DISPLAY 0.872340 (-3350 5900);
PAINT GREEN (-3350 5900);
DISPLAY INVISIBLE (-3350 5900);
FORCEPROP 1 LAST HDL_TAP TRUE
J 0
(-3025 5725);
DISPLAY 0.872340 (-3025 5725);
DISPLAY INVISIBLE (-3025 5725);
FORCEPROP 1 LAST PATH I163
J 0
(-3352 5850);
DISPLAY 0.872340 (-3352 5850);
PAINT GREEN (-3352 5850);
DISPLAY INVISIBLE (-3352 5850);
FORCEADD TAP..1
(-3350 5750);
FORCEPROP 3 LASTPIN (-3400 5750) SIG_NAME M_H_CPU1_SA_DQ<3>
J 0
(-3390 5760);
DISPLAY 0.659574 (-3390 5760);
PAINT MONO (-3390 5760);
DISPLAY INVISIBLE (-3390 5760);
FORCEPROP 1 LASTPIN (-3400 5750) BN 3
J 0
(-3412 5758);
DISPLAY 0.489362 (-3412 5758);
PAINT GREEN (-3412 5758);
FORCEPROP 2 LAST CDS_LIB mstr_standard
J 0
(-3350 5750);
DISPLAY 0.723404 (-3350 5750);
PAINT MONO (-3350 5750);
DISPLAY INVISIBLE (-3350 5750);
FORCEPROP 1 LAST BODY_TYPE PLUMBING
J 0
(-3350 5800);
DISPLAY 0.872340 (-3350 5800);
PAINT GREEN (-3350 5800);
DISPLAY INVISIBLE (-3350 5800);
FORCEPROP 1 LAST HDL_TAP TRUE
J 0
(-3025 5625);
DISPLAY 0.872340 (-3025 5625);
DISPLAY INVISIBLE (-3025 5625);
FORCEPROP 1 LAST PATH I164
J 0
(-3352 5750);
DISPLAY 0.872340 (-3352 5750);
PAINT GREEN (-3352 5750);
DISPLAY INVISIBLE (-3352 5750);
FORCEADD TAP..1
(-3350 5700);
FORCEPROP 3 LASTPIN (-3400 5700) SIG_NAME M_H_CPU1_SA_DQ<4>
J 0
(-3390 5710);
DISPLAY 0.659574 (-3390 5710);
PAINT MONO (-3390 5710);
DISPLAY INVISIBLE (-3390 5710);
FORCEPROP 1 LASTPIN (-3400 5700) BN 4
J 0
(-3412 5708);
DISPLAY 0.489362 (-3412 5708);
PAINT GREEN (-3412 5708);
FORCEPROP 2 LAST CDS_LIB mstr_standard
J 0
(-3350 5700);
DISPLAY 0.723404 (-3350 5700);
PAINT MONO (-3350 5700);
DISPLAY INVISIBLE (-3350 5700);
FORCEPROP 1 LAST BODY_TYPE PLUMBING
J 0
(-3350 5750);
DISPLAY 0.872340 (-3350 5750);
PAINT GREEN (-3350 5750);
DISPLAY INVISIBLE (-3350 5750);
FORCEPROP 1 LAST HDL_TAP TRUE
J 0
(-3025 5575);
DISPLAY 0.872340 (-3025 5575);
DISPLAY INVISIBLE (-3025 5575);
FORCEPROP 1 LAST PATH I165
J 0
(-3352 5700);
DISPLAY 0.872340 (-3352 5700);
PAINT GREEN (-3352 5700);
DISPLAY INVISIBLE (-3352 5700);
FORCEADD TAP..1
(-3350 5650);
FORCEPROP 3 LASTPIN (-3400 5650) SIG_NAME M_H_CPU1_SA_DQ<5>
J 0
(-3390 5660);
DISPLAY 0.659574 (-3390 5660);
PAINT MONO (-3390 5660);
DISPLAY INVISIBLE (-3390 5660);
FORCEPROP 1 LASTPIN (-3400 5650) BN 5
J 0
(-3412 5658);
DISPLAY 0.489362 (-3412 5658);
PAINT GREEN (-3412 5658);
FORCEPROP 2 LAST CDS_LIB mstr_standard
J 0
(-3350 5650);
DISPLAY 0.723404 (-3350 5650);
PAINT MONO (-3350 5650);
DISPLAY INVISIBLE (-3350 5650);
FORCEPROP 1 LAST BODY_TYPE PLUMBING
J 0
(-3350 5700);
DISPLAY 0.872340 (-3350 5700);
PAINT GREEN (-3350 5700);
DISPLAY INVISIBLE (-3350 5700);
FORCEPROP 1 LAST HDL_TAP TRUE
J 0
(-3025 5525);
DISPLAY 0.872340 (-3025 5525);
DISPLAY INVISIBLE (-3025 5525);
FORCEPROP 1 LAST PATH I166
J 0
(-3352 5650);
DISPLAY 0.872340 (-3352 5650);
PAINT GREEN (-3352 5650);
DISPLAY INVISIBLE (-3352 5650);
FORCEADD TAP..1
(-3350 5400);
FORCEPROP 3 LASTPIN (-3400 5400) SIG_NAME M_H_CPU1_SA_DQ<9>
J 0
(-3390 5410);
DISPLAY 0.659574 (-3390 5410);
PAINT MONO (-3390 5410);
DISPLAY INVISIBLE (-3390 5410);
FORCEPROP 1 LASTPIN (-3400 5400) BN 9
J 0
(-3412 5408);
DISPLAY 0.489362 (-3412 5408);
PAINT GREEN (-3412 5408);
FORCEPROP 2 LAST CDS_LIB mstr_standard
J 0
(-3350 5400);
DISPLAY 0.723404 (-3350 5400);
PAINT MONO (-3350 5400);
DISPLAY INVISIBLE (-3350 5400);
FORCEPROP 1 LAST BODY_TYPE PLUMBING
J 0
(-3350 5450);
DISPLAY 0.872340 (-3350 5450);
PAINT GREEN (-3350 5450);
DISPLAY INVISIBLE (-3350 5450);
FORCEPROP 1 LAST HDL_TAP TRUE
J 0
(-3025 5275);
DISPLAY 0.872340 (-3025 5275);
DISPLAY INVISIBLE (-3025 5275);
FORCEPROP 1 LAST PATH I167
J 0
(-3352 5400);
DISPLAY 0.872340 (-3352 5400);
PAINT GREEN (-3352 5400);
DISPLAY INVISIBLE (-3352 5400);
FORCEADD TAP..1
(-3350 5550);
FORCEPROP 3 LASTPIN (-3400 5550) SIG_NAME M_H_CPU1_SA_DQ<7>
J 0
(-3390 5560);
DISPLAY 0.659574 (-3390 5560);
PAINT MONO (-3390 5560);
DISPLAY INVISIBLE (-3390 5560);
FORCEPROP 1 LASTPIN (-3400 5550) BN 7
J 0
(-3412 5558);
DISPLAY 0.489362 (-3412 5558);
PAINT GREEN (-3412 5558);
FORCEPROP 2 LAST CDS_LIB mstr_standard
J 0
(-3350 5550);
DISPLAY 0.723404 (-3350 5550);
PAINT MONO (-3350 5550);
DISPLAY INVISIBLE (-3350 5550);
FORCEPROP 1 LAST BODY_TYPE PLUMBING
J 0
(-3350 5600);
DISPLAY 0.872340 (-3350 5600);
PAINT GREEN (-3350 5600);
DISPLAY INVISIBLE (-3350 5600);
FORCEPROP 1 LAST HDL_TAP TRUE
J 0
(-3025 5425);
DISPLAY 0.872340 (-3025 5425);
DISPLAY INVISIBLE (-3025 5425);
FORCEPROP 1 LAST PATH I168
J 0
(-3352 5550);
DISPLAY 0.872340 (-3352 5550);
PAINT GREEN (-3352 5550);
DISPLAY INVISIBLE (-3352 5550);
FORCEADD TAP..1
(-3350 5600);
FORCEPROP 3 LASTPIN (-3400 5600) SIG_NAME M_H_CPU1_SA_DQ<6>
J 0
(-3390 5610);
DISPLAY 0.659574 (-3390 5610);
PAINT MONO (-3390 5610);
DISPLAY INVISIBLE (-3390 5610);
FORCEPROP 1 LASTPIN (-3400 5600) BN 6
J 0
(-3412 5608);
DISPLAY 0.489362 (-3412 5608);
PAINT GREEN (-3412 5608);
FORCEPROP 2 LAST CDS_LIB mstr_standard
J 0
(-3350 5600);
DISPLAY 0.723404 (-3350 5600);
PAINT MONO (-3350 5600);
DISPLAY INVISIBLE (-3350 5600);
FORCEPROP 1 LAST BODY_TYPE PLUMBING
J 0
(-3350 5650);
DISPLAY 0.872340 (-3350 5650);
PAINT GREEN (-3350 5650);
DISPLAY INVISIBLE (-3350 5650);
FORCEPROP 1 LAST HDL_TAP TRUE
J 0
(-3025 5475);
DISPLAY 0.872340 (-3025 5475);
DISPLAY INVISIBLE (-3025 5475);
FORCEPROP 1 LAST PATH I169
J 0
(-3352 5600);
DISPLAY 0.872340 (-3352 5600);
PAINT GREEN (-3352 5600);
DISPLAY INVISIBLE (-3352 5600);
FORCEADD TAP..1
(-3350 5450);
FORCEPROP 3 LASTPIN (-3400 5450) SIG_NAME M_H_CPU1_SA_DQ<8>
J 0
(-3390 5460);
DISPLAY 0.659574 (-3390 5460);
PAINT MONO (-3390 5460);
DISPLAY INVISIBLE (-3390 5460);
FORCEPROP 1 LASTPIN (-3400 5450) BN 8
J 0
(-3412 5458);
DISPLAY 0.489362 (-3412 5458);
PAINT GREEN (-3412 5458);
FORCEPROP 2 LAST CDS_LIB mstr_standard
J 0
(-3350 5450);
DISPLAY 0.723404 (-3350 5450);
PAINT MONO (-3350 5450);
DISPLAY INVISIBLE (-3350 5450);
FORCEPROP 1 LAST BODY_TYPE PLUMBING
J 0
(-3350 5500);
DISPLAY 0.872340 (-3350 5500);
PAINT GREEN (-3350 5500);
DISPLAY INVISIBLE (-3350 5500);
FORCEPROP 1 LAST HDL_TAP TRUE
J 0
(-3025 5325);
DISPLAY 0.872340 (-3025 5325);
DISPLAY INVISIBLE (-3025 5325);
FORCEPROP 1 LAST PATH I170
J 0
(-3352 5450);
DISPLAY 0.872340 (-3352 5450);
PAINT GREEN (-3352 5450);
DISPLAY INVISIBLE (-3352 5450);
FORCEADD TAP..1
(-3350 5350);
FORCEPROP 3 LASTPIN (-3400 5350) SIG_NAME M_H_CPU1_SA_DQ<10>
J 0
(-3390 5360);
DISPLAY 0.659574 (-3390 5360);
PAINT MONO (-3390 5360);
DISPLAY INVISIBLE (-3390 5360);
FORCEPROP 1 LASTPIN (-3400 5350) BN 10
J 0
(-3412 5358);
DISPLAY 0.489362 (-3412 5358);
PAINT GREEN (-3412 5358);
FORCEPROP 2 LAST CDS_LIB mstr_standard
J 0
(-3350 5350);
DISPLAY 0.723404 (-3350 5350);
PAINT MONO (-3350 5350);
DISPLAY INVISIBLE (-3350 5350);
FORCEPROP 1 LAST BODY_TYPE PLUMBING
J 0
(-3350 5400);
DISPLAY 0.872340 (-3350 5400);
PAINT GREEN (-3350 5400);
DISPLAY INVISIBLE (-3350 5400);
FORCEPROP 1 LAST HDL_TAP TRUE
J 0
(-3025 5225);
DISPLAY 0.872340 (-3025 5225);
DISPLAY INVISIBLE (-3025 5225);
FORCEPROP 1 LAST PATH I171
J 0
(-3352 5350);
DISPLAY 0.872340 (-3352 5350);
PAINT GREEN (-3352 5350);
DISPLAY INVISIBLE (-3352 5350);
FORCEADD TAP..1
(-3350 5250);
FORCEPROP 3 LASTPIN (-3400 5250) SIG_NAME M_H_CPU1_SA_DQ<12>
J 0
(-3390 5260);
DISPLAY 0.659574 (-3390 5260);
PAINT MONO (-3390 5260);
DISPLAY INVISIBLE (-3390 5260);
FORCEPROP 1 LASTPIN (-3400 5250) BN 12
J 0
(-3412 5258);
DISPLAY 0.489362 (-3412 5258);
PAINT GREEN (-3412 5258);
FORCEPROP 2 LAST CDS_LIB mstr_standard
J 0
(-3350 5250);
DISPLAY 0.723404 (-3350 5250);
PAINT MONO (-3350 5250);
DISPLAY INVISIBLE (-3350 5250);
FORCEPROP 1 LAST BODY_TYPE PLUMBING
J 0
(-3350 5300);
DISPLAY 0.872340 (-3350 5300);
PAINT GREEN (-3350 5300);
DISPLAY INVISIBLE (-3350 5300);
FORCEPROP 1 LAST HDL_TAP TRUE
J 0
(-3025 5125);
DISPLAY 0.872340 (-3025 5125);
DISPLAY INVISIBLE (-3025 5125);
FORCEPROP 1 LAST PATH I172
J 0
(-3352 5250);
DISPLAY 0.872340 (-3352 5250);
PAINT GREEN (-3352 5250);
DISPLAY INVISIBLE (-3352 5250);
FORCEADD TAP..1
(-3350 5300);
FORCEPROP 3 LASTPIN (-3400 5300) SIG_NAME M_H_CPU1_SA_DQ<11>
J 0
(-3390 5310);
DISPLAY 0.659574 (-3390 5310);
PAINT MONO (-3390 5310);
DISPLAY INVISIBLE (-3390 5310);
FORCEPROP 1 LASTPIN (-3400 5300) BN 11
J 0
(-3412 5308);
DISPLAY 0.489362 (-3412 5308);
PAINT GREEN (-3412 5308);
FORCEPROP 2 LAST CDS_LIB mstr_standard
J 0
(-3350 5300);
DISPLAY 0.723404 (-3350 5300);
PAINT MONO (-3350 5300);
DISPLAY INVISIBLE (-3350 5300);
FORCEPROP 1 LAST BODY_TYPE PLUMBING
J 0
(-3350 5350);
DISPLAY 0.872340 (-3350 5350);
PAINT GREEN (-3350 5350);
DISPLAY INVISIBLE (-3350 5350);
FORCEPROP 1 LAST HDL_TAP TRUE
J 0
(-3025 5175);
DISPLAY 0.872340 (-3025 5175);
DISPLAY INVISIBLE (-3025 5175);
FORCEPROP 1 LAST PATH I173
J 0
(-3352 5300);
DISPLAY 0.872340 (-3352 5300);
PAINT GREEN (-3352 5300);
DISPLAY INVISIBLE (-3352 5300);
FORCEADD TAP..1
(-3350 5150);
FORCEPROP 3 LASTPIN (-3400 5150) SIG_NAME M_H_CPU1_SA_DQ<14>
J 0
(-3390 5160);
DISPLAY 0.659574 (-3390 5160);
PAINT MONO (-3390 5160);
DISPLAY INVISIBLE (-3390 5160);
FORCEPROP 1 LASTPIN (-3400 5150) BN 14
J 0
(-3412 5158);
DISPLAY 0.489362 (-3412 5158);
PAINT GREEN (-3412 5158);
FORCEPROP 2 LAST CDS_LIB mstr_standard
J 0
(-3350 5150);
DISPLAY 0.723404 (-3350 5150);
PAINT MONO (-3350 5150);
DISPLAY INVISIBLE (-3350 5150);
FORCEPROP 1 LAST BODY_TYPE PLUMBING
J 0
(-3350 5200);
DISPLAY 0.872340 (-3350 5200);
PAINT GREEN (-3350 5200);
DISPLAY INVISIBLE (-3350 5200);
FORCEPROP 1 LAST HDL_TAP TRUE
J 0
(-3025 5025);
DISPLAY 0.872340 (-3025 5025);
DISPLAY INVISIBLE (-3025 5025);
FORCEPROP 1 LAST PATH I174
J 0
(-3352 5150);
DISPLAY 0.872340 (-3352 5150);
PAINT GREEN (-3352 5150);
DISPLAY INVISIBLE (-3352 5150);
FORCEADD TAP..1
(-3350 5200);
FORCEPROP 3 LASTPIN (-3400 5200) SIG_NAME M_H_CPU1_SA_DQ<13>
J 0
(-3390 5210);
DISPLAY 0.659574 (-3390 5210);
PAINT MONO (-3390 5210);
DISPLAY INVISIBLE (-3390 5210);
FORCEPROP 1 LASTPIN (-3400 5200) BN 13
J 0
(-3412 5208);
DISPLAY 0.489362 (-3412 5208);
PAINT GREEN (-3412 5208);
FORCEPROP 2 LAST CDS_LIB mstr_standard
J 0
(-3350 5200);
DISPLAY 0.723404 (-3350 5200);
PAINT MONO (-3350 5200);
DISPLAY INVISIBLE (-3350 5200);
FORCEPROP 1 LAST BODY_TYPE PLUMBING
J 0
(-3350 5250);
DISPLAY 0.872340 (-3350 5250);
PAINT GREEN (-3350 5250);
DISPLAY INVISIBLE (-3350 5250);
FORCEPROP 1 LAST HDL_TAP TRUE
J 0
(-3025 5075);
DISPLAY 0.872340 (-3025 5075);
DISPLAY INVISIBLE (-3025 5075);
FORCEPROP 1 LAST PATH I175
J 0
(-3352 5200);
DISPLAY 0.872340 (-3352 5200);
PAINT GREEN (-3352 5200);
DISPLAY INVISIBLE (-3352 5200);
FORCEADD TAP..1
(-3350 5000);
FORCEPROP 3 LASTPIN (-3400 5000) SIG_NAME M_H_CPU1_SA_DQ<16>
J 0
(-3390 5010);
DISPLAY 0.659574 (-3390 5010);
PAINT MONO (-3390 5010);
DISPLAY INVISIBLE (-3390 5010);
FORCEPROP 1 LASTPIN (-3400 5000) BN 16
J 0
(-3412 5008);
DISPLAY 0.489362 (-3412 5008);
PAINT GREEN (-3412 5008);
FORCEPROP 2 LAST CDS_LIB mstr_standard
J 0
(-3350 5000);
DISPLAY 0.723404 (-3350 5000);
PAINT MONO (-3350 5000);
DISPLAY INVISIBLE (-3350 5000);
FORCEPROP 1 LAST BODY_TYPE PLUMBING
J 0
(-3350 5050);
DISPLAY 0.872340 (-3350 5050);
PAINT GREEN (-3350 5050);
DISPLAY INVISIBLE (-3350 5050);
FORCEPROP 1 LAST HDL_TAP TRUE
J 0
(-3025 4875);
DISPLAY 0.872340 (-3025 4875);
DISPLAY INVISIBLE (-3025 4875);
FORCEPROP 1 LAST PATH I176
J 0
(-3352 5000);
DISPLAY 0.872340 (-3352 5000);
PAINT GREEN (-3352 5000);
DISPLAY INVISIBLE (-3352 5000);
FORCEADD TAP..1
(-3350 5100);
FORCEPROP 3 LASTPIN (-3400 5100) SIG_NAME M_H_CPU1_SA_DQ<15>
J 0
(-3390 5110);
DISPLAY 0.659574 (-3390 5110);
PAINT MONO (-3390 5110);
DISPLAY INVISIBLE (-3390 5110);
FORCEPROP 1 LASTPIN (-3400 5100) BN 15
J 0
(-3412 5108);
DISPLAY 0.489362 (-3412 5108);
PAINT GREEN (-3412 5108);
FORCEPROP 2 LAST CDS_LIB mstr_standard
J 0
(-3350 5100);
DISPLAY 0.723404 (-3350 5100);
PAINT MONO (-3350 5100);
DISPLAY INVISIBLE (-3350 5100);
FORCEPROP 1 LAST BODY_TYPE PLUMBING
J 0
(-3350 5150);
DISPLAY 0.872340 (-3350 5150);
PAINT GREEN (-3350 5150);
DISPLAY INVISIBLE (-3350 5150);
FORCEPROP 1 LAST HDL_TAP TRUE
J 0
(-3025 4975);
DISPLAY 0.872340 (-3025 4975);
DISPLAY INVISIBLE (-3025 4975);
FORCEPROP 1 LAST PATH I177
J 0
(-3352 5100);
DISPLAY 0.872340 (-3352 5100);
PAINT GREEN (-3352 5100);
DISPLAY INVISIBLE (-3352 5100);
FORCEADD TAP..1
(-3350 4900);
FORCEPROP 3 LASTPIN (-3400 4900) SIG_NAME M_H_CPU1_SA_DQ<18>
J 0
(-3390 4910);
DISPLAY 0.659574 (-3390 4910);
PAINT MONO (-3390 4910);
DISPLAY INVISIBLE (-3390 4910);
FORCEPROP 1 LASTPIN (-3400 4900) BN 18
J 0
(-3412 4908);
DISPLAY 0.489362 (-3412 4908);
PAINT GREEN (-3412 4908);
FORCEPROP 2 LAST CDS_LIB mstr_standard
J 0
(-3350 4900);
DISPLAY 0.723404 (-3350 4900);
PAINT MONO (-3350 4900);
DISPLAY INVISIBLE (-3350 4900);
FORCEPROP 1 LAST BODY_TYPE PLUMBING
J 0
(-3350 4950);
DISPLAY 0.872340 (-3350 4950);
PAINT GREEN (-3350 4950);
DISPLAY INVISIBLE (-3350 4950);
FORCEPROP 1 LAST HDL_TAP TRUE
J 0
(-3025 4775);
DISPLAY 0.872340 (-3025 4775);
DISPLAY INVISIBLE (-3025 4775);
FORCEPROP 1 LAST PATH I178
J 0
(-3352 4900);
DISPLAY 0.872340 (-3352 4900);
PAINT GREEN (-3352 4900);
DISPLAY INVISIBLE (-3352 4900);
FORCEADD TAP..1
(-3350 4950);
FORCEPROP 3 LASTPIN (-3400 4950) SIG_NAME M_H_CPU1_SA_DQ<17>
J 0
(-3390 4960);
DISPLAY 0.659574 (-3390 4960);
PAINT MONO (-3390 4960);
DISPLAY INVISIBLE (-3390 4960);
FORCEPROP 1 LASTPIN (-3400 4950) BN 17
J 0
(-3412 4958);
DISPLAY 0.489362 (-3412 4958);
PAINT GREEN (-3412 4958);
FORCEPROP 2 LAST CDS_LIB mstr_standard
J 0
(-3350 4950);
DISPLAY 0.723404 (-3350 4950);
PAINT MONO (-3350 4950);
DISPLAY INVISIBLE (-3350 4950);
FORCEPROP 1 LAST BODY_TYPE PLUMBING
J 0
(-3350 5000);
DISPLAY 0.872340 (-3350 5000);
PAINT GREEN (-3350 5000);
DISPLAY INVISIBLE (-3350 5000);
FORCEPROP 1 LAST HDL_TAP TRUE
J 0
(-3025 4825);
DISPLAY 0.872340 (-3025 4825);
DISPLAY INVISIBLE (-3025 4825);
FORCEPROP 1 LAST PATH I179
J 0
(-3352 4950);
DISPLAY 0.872340 (-3352 4950);
PAINT GREEN (-3352 4950);
DISPLAY INVISIBLE (-3352 4950);
FORCEADD TAP..1
(-3350 4800);
FORCEPROP 3 LASTPIN (-3400 4800) SIG_NAME M_H_CPU1_SA_DQ<20>
J 0
(-3390 4810);
DISPLAY 0.659574 (-3390 4810);
PAINT MONO (-3390 4810);
DISPLAY INVISIBLE (-3390 4810);
FORCEPROP 1 LASTPIN (-3400 4800) BN 20
J 0
(-3412 4808);
DISPLAY 0.489362 (-3412 4808);
PAINT GREEN (-3412 4808);
FORCEPROP 2 LAST CDS_LIB mstr_standard
J 0
(-3350 4800);
DISPLAY 0.723404 (-3350 4800);
PAINT MONO (-3350 4800);
DISPLAY INVISIBLE (-3350 4800);
FORCEPROP 1 LAST BODY_TYPE PLUMBING
J 0
(-3350 4850);
DISPLAY 0.872340 (-3350 4850);
PAINT GREEN (-3350 4850);
DISPLAY INVISIBLE (-3350 4850);
FORCEPROP 1 LAST HDL_TAP TRUE
J 0
(-3025 4675);
DISPLAY 0.872340 (-3025 4675);
DISPLAY INVISIBLE (-3025 4675);
FORCEPROP 1 LAST PATH I180
J 0
(-3352 4800);
DISPLAY 0.872340 (-3352 4800);
PAINT GREEN (-3352 4800);
DISPLAY INVISIBLE (-3352 4800);
FORCEADD TAP..1
(-3350 4850);
FORCEPROP 3 LASTPIN (-3400 4850) SIG_NAME M_H_CPU1_SA_DQ<19>
J 0
(-3390 4860);
DISPLAY 0.659574 (-3390 4860);
PAINT MONO (-3390 4860);
DISPLAY INVISIBLE (-3390 4860);
FORCEPROP 1 LASTPIN (-3400 4850) BN 19
J 0
(-3412 4858);
DISPLAY 0.489362 (-3412 4858);
PAINT GREEN (-3412 4858);
FORCEPROP 2 LAST CDS_LIB mstr_standard
J 0
(-3350 4850);
DISPLAY 0.723404 (-3350 4850);
PAINT MONO (-3350 4850);
DISPLAY INVISIBLE (-3350 4850);
FORCEPROP 1 LAST BODY_TYPE PLUMBING
J 0
(-3350 4900);
DISPLAY 0.872340 (-3350 4900);
PAINT GREEN (-3350 4900);
DISPLAY INVISIBLE (-3350 4900);
FORCEPROP 1 LAST HDL_TAP TRUE
J 0
(-3025 4725);
DISPLAY 0.872340 (-3025 4725);
DISPLAY INVISIBLE (-3025 4725);
FORCEPROP 1 LAST PATH I181
J 0
(-3352 4850);
DISPLAY 0.872340 (-3352 4850);
PAINT GREEN (-3352 4850);
DISPLAY INVISIBLE (-3352 4850);
FORCEADD TAP..1
(-3350 4750);
FORCEPROP 3 LASTPIN (-3400 4750) SIG_NAME M_H_CPU1_SA_DQ<21>
J 0
(-3390 4760);
DISPLAY 0.659574 (-3390 4760);
PAINT MONO (-3390 4760);
DISPLAY INVISIBLE (-3390 4760);
FORCEPROP 1 LASTPIN (-3400 4750) BN 21
J 0
(-3412 4758);
DISPLAY 0.489362 (-3412 4758);
PAINT GREEN (-3412 4758);
FORCEPROP 2 LAST CDS_LIB mstr_standard
J 0
(-3350 4750);
DISPLAY 0.723404 (-3350 4750);
PAINT MONO (-3350 4750);
DISPLAY INVISIBLE (-3350 4750);
FORCEPROP 1 LAST BODY_TYPE PLUMBING
J 0
(-3350 4800);
DISPLAY 0.872340 (-3350 4800);
PAINT GREEN (-3350 4800);
DISPLAY INVISIBLE (-3350 4800);
FORCEPROP 1 LAST HDL_TAP TRUE
J 0
(-3025 4625);
DISPLAY 0.872340 (-3025 4625);
DISPLAY INVISIBLE (-3025 4625);
FORCEPROP 1 LAST PATH I182
J 0
(-3352 4750);
DISPLAY 0.872340 (-3352 4750);
PAINT GREEN (-3352 4750);
DISPLAY INVISIBLE (-3352 4750);
FORCEADD TAP..1
(-3350 4650);
FORCEPROP 3 LASTPIN (-3400 4650) SIG_NAME M_H_CPU1_SA_DQ<23>
J 0
(-3390 4660);
DISPLAY 0.659574 (-3390 4660);
PAINT MONO (-3390 4660);
DISPLAY INVISIBLE (-3390 4660);
FORCEPROP 1 LASTPIN (-3400 4650) BN 23
J 0
(-3412 4658);
DISPLAY 0.489362 (-3412 4658);
PAINT GREEN (-3412 4658);
FORCEPROP 2 LAST CDS_LIB mstr_standard
J 0
(-3350 4650);
DISPLAY 0.723404 (-3350 4650);
PAINT MONO (-3350 4650);
DISPLAY INVISIBLE (-3350 4650);
FORCEPROP 1 LAST BODY_TYPE PLUMBING
J 0
(-3350 4700);
DISPLAY 0.872340 (-3350 4700);
PAINT GREEN (-3350 4700);
DISPLAY INVISIBLE (-3350 4700);
FORCEPROP 1 LAST HDL_TAP TRUE
J 0
(-3025 4525);
DISPLAY 0.872340 (-3025 4525);
DISPLAY INVISIBLE (-3025 4525);
FORCEPROP 1 LAST PATH I183
J 0
(-3352 4650);
DISPLAY 0.872340 (-3352 4650);
PAINT GREEN (-3352 4650);
DISPLAY INVISIBLE (-3352 4650);
FORCEADD TAP..1
(-3350 4700);
FORCEPROP 3 LASTPIN (-3400 4700) SIG_NAME M_H_CPU1_SA_DQ<22>
J 0
(-3390 4710);
DISPLAY 0.659574 (-3390 4710);
PAINT MONO (-3390 4710);
DISPLAY INVISIBLE (-3390 4710);
FORCEPROP 1 LASTPIN (-3400 4700) BN 22
J 0
(-3412 4708);
DISPLAY 0.489362 (-3412 4708);
PAINT GREEN (-3412 4708);
FORCEPROP 2 LAST CDS_LIB mstr_standard
J 0
(-3350 4700);
DISPLAY 0.723404 (-3350 4700);
PAINT MONO (-3350 4700);
DISPLAY INVISIBLE (-3350 4700);
FORCEPROP 1 LAST BODY_TYPE PLUMBING
J 0
(-3350 4750);
DISPLAY 0.872340 (-3350 4750);
PAINT GREEN (-3350 4750);
DISPLAY INVISIBLE (-3350 4750);
FORCEPROP 1 LAST HDL_TAP TRUE
J 0
(-3025 4575);
DISPLAY 0.872340 (-3025 4575);
DISPLAY INVISIBLE (-3025 4575);
FORCEPROP 1 LAST PATH I184
J 0
(-3352 4700);
DISPLAY 0.872340 (-3352 4700);
PAINT GREEN (-3352 4700);
DISPLAY INVISIBLE (-3352 4700);
FORCEADD TAP..1
(-3350 4550);
FORCEPROP 3 LASTPIN (-3400 4550) SIG_NAME M_H_CPU1_SA_DQ<24>
J 0
(-3390 4560);
DISPLAY 0.659574 (-3390 4560);
PAINT MONO (-3390 4560);
DISPLAY INVISIBLE (-3390 4560);
FORCEPROP 1 LASTPIN (-3400 4550) BN 24
J 0
(-3412 4558);
DISPLAY 0.489362 (-3412 4558);
PAINT GREEN (-3412 4558);
FORCEPROP 2 LAST CDS_LIB mstr_standard
J 0
(-3350 4550);
DISPLAY 0.723404 (-3350 4550);
PAINT MONO (-3350 4550);
DISPLAY INVISIBLE (-3350 4550);
FORCEPROP 1 LAST BODY_TYPE PLUMBING
J 0
(-3350 4600);
DISPLAY 0.872340 (-3350 4600);
PAINT GREEN (-3350 4600);
DISPLAY INVISIBLE (-3350 4600);
FORCEPROP 1 LAST HDL_TAP TRUE
J 0
(-3025 4425);
DISPLAY 0.872340 (-3025 4425);
DISPLAY INVISIBLE (-3025 4425);
FORCEPROP 1 LAST PATH I185
J 0
(-3352 4550);
DISPLAY 0.872340 (-3352 4550);
PAINT GREEN (-3352 4550);
DISPLAY INVISIBLE (-3352 4550);
FORCEADD TAP..1
(-3350 4500);
FORCEPROP 3 LASTPIN (-3400 4500) SIG_NAME M_H_CPU1_SA_DQ<25>
J 0
(-3390 4510);
DISPLAY 0.659574 (-3390 4510);
PAINT MONO (-3390 4510);
DISPLAY INVISIBLE (-3390 4510);
FORCEPROP 1 LASTPIN (-3400 4500) BN 25
J 0
(-3412 4508);
DISPLAY 0.489362 (-3412 4508);
PAINT GREEN (-3412 4508);
FORCEPROP 2 LAST CDS_LIB mstr_standard
J 0
(-3350 4500);
DISPLAY 0.723404 (-3350 4500);
PAINT MONO (-3350 4500);
DISPLAY INVISIBLE (-3350 4500);
FORCEPROP 1 LAST BODY_TYPE PLUMBING
J 0
(-3350 4550);
DISPLAY 0.872340 (-3350 4550);
PAINT GREEN (-3350 4550);
DISPLAY INVISIBLE (-3350 4550);
FORCEPROP 1 LAST HDL_TAP TRUE
J 0
(-3025 4375);
DISPLAY 0.872340 (-3025 4375);
DISPLAY INVISIBLE (-3025 4375);
FORCEPROP 1 LAST PATH I186
J 0
(-3352 4500);
DISPLAY 0.872340 (-3352 4500);
PAINT GREEN (-3352 4500);
DISPLAY INVISIBLE (-3352 4500);
FORCEADD TAP..1
(-3350 4400);
FORCEPROP 3 LASTPIN (-3400 4400) SIG_NAME M_H_CPU1_SA_DQ<27>
J 0
(-3390 4410);
DISPLAY 0.659574 (-3390 4410);
PAINT MONO (-3390 4410);
DISPLAY INVISIBLE (-3390 4410);
FORCEPROP 1 LASTPIN (-3400 4400) BN 27
J 0
(-3412 4408);
DISPLAY 0.489362 (-3412 4408);
PAINT GREEN (-3412 4408);
FORCEPROP 2 LAST CDS_LIB mstr_standard
J 0
(-3350 4400);
DISPLAY 0.723404 (-3350 4400);
PAINT MONO (-3350 4400);
DISPLAY INVISIBLE (-3350 4400);
FORCEPROP 1 LAST BODY_TYPE PLUMBING
J 0
(-3350 4450);
DISPLAY 0.872340 (-3350 4450);
PAINT GREEN (-3350 4450);
DISPLAY INVISIBLE (-3350 4450);
FORCEPROP 1 LAST HDL_TAP TRUE
J 0
(-3025 4275);
DISPLAY 0.872340 (-3025 4275);
DISPLAY INVISIBLE (-3025 4275);
FORCEPROP 1 LAST PATH I187
J 0
(-3352 4400);
DISPLAY 0.872340 (-3352 4400);
PAINT GREEN (-3352 4400);
DISPLAY INVISIBLE (-3352 4400);
FORCEADD TAP..1
(-3350 4450);
FORCEPROP 3 LASTPIN (-3400 4450) SIG_NAME M_H_CPU1_SA_DQ<26>
J 0
(-3390 4460);
DISPLAY 0.659574 (-3390 4460);
PAINT MONO (-3390 4460);
DISPLAY INVISIBLE (-3390 4460);
FORCEPROP 1 LASTPIN (-3400 4450) BN 26
J 0
(-3412 4458);
DISPLAY 0.489362 (-3412 4458);
PAINT GREEN (-3412 4458);
FORCEPROP 2 LAST CDS_LIB mstr_standard
J 0
(-3350 4450);
DISPLAY 0.723404 (-3350 4450);
PAINT MONO (-3350 4450);
DISPLAY INVISIBLE (-3350 4450);
FORCEPROP 1 LAST BODY_TYPE PLUMBING
J 0
(-3350 4500);
DISPLAY 0.872340 (-3350 4500);
PAINT GREEN (-3350 4500);
DISPLAY INVISIBLE (-3350 4500);
FORCEPROP 1 LAST HDL_TAP TRUE
J 0
(-3025 4325);
DISPLAY 0.872340 (-3025 4325);
DISPLAY INVISIBLE (-3025 4325);
FORCEPROP 1 LAST PATH I188
J 0
(-3352 4450);
DISPLAY 0.872340 (-3352 4450);
PAINT GREEN (-3352 4450);
DISPLAY INVISIBLE (-3352 4450);
FORCEADD TAP..1
(-3350 4300);
FORCEPROP 3 LASTPIN (-3400 4300) SIG_NAME M_H_CPU1_SA_DQ<29>
J 0
(-3390 4310);
DISPLAY 0.659574 (-3390 4310);
PAINT MONO (-3390 4310);
DISPLAY INVISIBLE (-3390 4310);
FORCEPROP 1 LASTPIN (-3400 4300) BN 29
J 0
(-3412 4308);
DISPLAY 0.489362 (-3412 4308);
PAINT GREEN (-3412 4308);
FORCEPROP 2 LAST CDS_LIB mstr_standard
J 0
(-3350 4300);
DISPLAY 0.723404 (-3350 4300);
PAINT MONO (-3350 4300);
DISPLAY INVISIBLE (-3350 4300);
FORCEPROP 1 LAST BODY_TYPE PLUMBING
J 0
(-3350 4350);
DISPLAY 0.872340 (-3350 4350);
PAINT GREEN (-3350 4350);
DISPLAY INVISIBLE (-3350 4350);
FORCEPROP 1 LAST HDL_TAP TRUE
J 0
(-3025 4175);
DISPLAY 0.872340 (-3025 4175);
DISPLAY INVISIBLE (-3025 4175);
FORCEPROP 1 LAST PATH I189
J 0
(-3352 4300);
DISPLAY 0.872340 (-3352 4300);
PAINT GREEN (-3352 4300);
DISPLAY INVISIBLE (-3352 4300);
FORCEADD TAP..1
(-3350 4350);
FORCEPROP 3 LASTPIN (-3400 4350) SIG_NAME M_H_CPU1_SA_DQ<28>
J 0
(-3390 4360);
DISPLAY 0.659574 (-3390 4360);
PAINT MONO (-3390 4360);
DISPLAY INVISIBLE (-3390 4360);
FORCEPROP 1 LASTPIN (-3400 4350) BN 28
J 0
(-3412 4358);
DISPLAY 0.489362 (-3412 4358);
PAINT GREEN (-3412 4358);
FORCEPROP 2 LAST CDS_LIB mstr_standard
J 0
(-3350 4350);
DISPLAY 0.723404 (-3350 4350);
PAINT MONO (-3350 4350);
DISPLAY INVISIBLE (-3350 4350);
FORCEPROP 1 LAST BODY_TYPE PLUMBING
J 0
(-3350 4400);
DISPLAY 0.872340 (-3350 4400);
PAINT GREEN (-3350 4400);
DISPLAY INVISIBLE (-3350 4400);
FORCEPROP 1 LAST HDL_TAP TRUE
J 0
(-3025 4225);
DISPLAY 0.872340 (-3025 4225);
DISPLAY INVISIBLE (-3025 4225);
FORCEPROP 1 LAST PATH I190
J 0
(-3352 4350);
DISPLAY 0.872340 (-3352 4350);
PAINT GREEN (-3352 4350);
DISPLAY INVISIBLE (-3352 4350);
FORCEADD TAP..1
(-3350 4250);
FORCEPROP 3 LASTPIN (-3400 4250) SIG_NAME M_H_CPU1_SA_DQ<30>
J 0
(-3390 4260);
DISPLAY 0.659574 (-3390 4260);
PAINT MONO (-3390 4260);
DISPLAY INVISIBLE (-3390 4260);
FORCEPROP 1 LASTPIN (-3400 4250) BN 30
J 0
(-3412 4258);
DISPLAY 0.489362 (-3412 4258);
PAINT GREEN (-3412 4258);
FORCEPROP 2 LAST CDS_LIB mstr_standard
J 0
(-3350 4250);
DISPLAY 0.723404 (-3350 4250);
PAINT MONO (-3350 4250);
DISPLAY INVISIBLE (-3350 4250);
FORCEPROP 1 LAST BODY_TYPE PLUMBING
J 0
(-3350 4300);
DISPLAY 0.872340 (-3350 4300);
PAINT GREEN (-3350 4300);
DISPLAY INVISIBLE (-3350 4300);
FORCEPROP 1 LAST HDL_TAP TRUE
J 0
(-3025 4125);
DISPLAY 0.872340 (-3025 4125);
DISPLAY INVISIBLE (-3025 4125);
FORCEPROP 1 LAST PATH I191
J 0
(-3352 4250);
DISPLAY 0.872340 (-3352 4250);
PAINT GREEN (-3352 4250);
DISPLAY INVISIBLE (-3352 4250);
FORCEADD TAP..1
(-3350 4100);
FORCEPROP 3 LASTPIN (-3400 4100) SIG_NAME M_H_CPU1_SB_DQ<0>
J 0
(-3390 4110);
DISPLAY 0.659574 (-3390 4110);
PAINT MONO (-3390 4110);
DISPLAY INVISIBLE (-3390 4110);
FORCEPROP 1 LASTPIN (-3400 4100) BN 0
J 0
(-3412 4108);
DISPLAY 0.489362 (-3412 4108);
PAINT GREEN (-3412 4108);
FORCEPROP 2 LAST CDS_LIB mstr_standard
J 0
(-3350 4100);
DISPLAY 0.723404 (-3350 4100);
PAINT MONO (-3350 4100);
DISPLAY INVISIBLE (-3350 4100);
FORCEPROP 1 LAST BODY_TYPE PLUMBING
J 0
(-3350 4150);
DISPLAY 0.872340 (-3350 4150);
PAINT GREEN (-3350 4150);
DISPLAY INVISIBLE (-3350 4150);
FORCEPROP 1 LAST HDL_TAP TRUE
J 0
(-3025 3975);
DISPLAY 0.872340 (-3025 3975);
DISPLAY INVISIBLE (-3025 3975);
FORCEPROP 1 LAST PATH I192
J 0
(-3352 4100);
DISPLAY 0.872340 (-3352 4100);
PAINT GREEN (-3352 4100);
DISPLAY INVISIBLE (-3352 4100);
FORCEADD TAP..1
(-3350 4200);
FORCEPROP 3 LASTPIN (-3400 4200) SIG_NAME M_H_CPU1_SA_DQ<31>
J 0
(-3390 4210);
DISPLAY 0.659574 (-3390 4210);
PAINT MONO (-3390 4210);
DISPLAY INVISIBLE (-3390 4210);
FORCEPROP 1 LASTPIN (-3400 4200) BN 31
J 0
(-3412 4208);
DISPLAY 0.489362 (-3412 4208);
PAINT GREEN (-3412 4208);
FORCEPROP 2 LAST CDS_LIB mstr_standard
J 0
(-3350 4200);
DISPLAY 0.723404 (-3350 4200);
PAINT MONO (-3350 4200);
DISPLAY INVISIBLE (-3350 4200);
FORCEPROP 1 LAST BODY_TYPE PLUMBING
J 0
(-3350 4250);
DISPLAY 0.872340 (-3350 4250);
PAINT GREEN (-3350 4250);
DISPLAY INVISIBLE (-3350 4250);
FORCEPROP 1 LAST HDL_TAP TRUE
J 0
(-3025 4075);
DISPLAY 0.872340 (-3025 4075);
DISPLAY INVISIBLE (-3025 4075);
FORCEPROP 1 LAST PATH I193
J 0
(-3352 4200);
DISPLAY 0.872340 (-3352 4200);
PAINT GREEN (-3352 4200);
DISPLAY INVISIBLE (-3352 4200);
FORCEADD OFFPAGE..3
(-2625 4125);
FORCEPROP 2 LAST $XR0 104 
J 0
(-2411 4125);
DISPLAY 0.638298 (-2411 4125);
PAINT MONO (-2411 4125);
FORCEPROP 2 LAST PATH I194
J 0
(-2400 4175);
DISPLAY 1.021277 (-2400 4175);
DISPLAY INVISIBLE (-2400 4175);
FORCEPROP 1 LAST COMMENT_BODY TRUE
J 0
(-2675 4025);
DISPLAY 0.872340 (-2675 4025);
PAINT GREEN (-2675 4025);
DISPLAY INVISIBLE (-2675 4025);
FORCEPROP 1 LAST OFFPAGE TRUE
J 0
(-2300 4000);
DISPLAY 0.872340 (-2300 4000);
PAINT GREEN (-2300 4000);
DISPLAY INVISIBLE (-2300 4000);
FORCEPROP 2 LAST CDS_LIB mstr_standard
J 0
(-2625 4125);
DISPLAY 0.723404 (-2625 4125);
PAINT MONO (-2625 4125);
DISPLAY INVISIBLE (-2625 4125);
FORCEADD OFFPAGE..6
R 2
(-2750 2350);
FORCEPROP 2 LAST $XR0 104 
J 0
(-2536 2350);
DISPLAY 0.638298 (-2536 2350);
PAINT MONO (-2536 2350);
FORCEPROP 2 LAST PATH I195
J 0
(-2525 2400);
DISPLAY 1.021277 (-2525 2400);
DISPLAY INVISIBLE (-2525 2400);
FORCEPROP 1 LAST COMMENT_BODY TRUE
J 2
(-2850 2275);
DISPLAY 0.872340 (-2850 2275);
PAINT GREEN (-2850 2275);
DISPLAY INVISIBLE (-2850 2275);
FORCEPROP 1 LAST OFFPAGE TRUE
J 2
(-3075 2225);
DISPLAY 0.872340 (-3075 2225);
PAINT GREEN (-3075 2225);
DISPLAY INVISIBLE (-3075 2225);
FORCEPROP 2 LAST CDS_LIB mstr_standard
J 2
(-2750 2350);
DISPLAY 0.723404 (-2750 2350);
PAINT MONO (-2750 2350);
DISPLAY INVISIBLE (-2750 2350);
FORCEADD TAP..1
(-3350 4000);
FORCEPROP 3 LASTPIN (-3400 4000) SIG_NAME M_H_CPU1_SB_DQ<2>
J 0
(-3390 4010);
DISPLAY 0.659574 (-3390 4010);
PAINT MONO (-3390 4010);
DISPLAY INVISIBLE (-3390 4010);
FORCEPROP 1 LASTPIN (-3400 4000) BN 2
J 0
(-3412 4008);
DISPLAY 0.489362 (-3412 4008);
PAINT GREEN (-3412 4008);
FORCEPROP 2 LAST CDS_LIB mstr_standard
J 0
(-3350 4000);
DISPLAY 0.723404 (-3350 4000);
PAINT MONO (-3350 4000);
DISPLAY INVISIBLE (-3350 4000);
FORCEPROP 1 LAST BODY_TYPE PLUMBING
J 0
(-3350 4050);
DISPLAY 0.872340 (-3350 4050);
PAINT GREEN (-3350 4050);
DISPLAY INVISIBLE (-3350 4050);
FORCEPROP 1 LAST HDL_TAP TRUE
J 0
(-3025 3875);
DISPLAY 0.872340 (-3025 3875);
DISPLAY INVISIBLE (-3025 3875);
FORCEPROP 1 LAST PATH I196
J 0
(-3352 4000);
DISPLAY 0.872340 (-3352 4000);
PAINT GREEN (-3352 4000);
DISPLAY INVISIBLE (-3352 4000);
FORCEADD TAP..1
(-3350 4050);
FORCEPROP 3 LASTPIN (-3400 4050) SIG_NAME M_H_CPU1_SB_DQ<1>
J 0
(-3390 4060);
DISPLAY 0.659574 (-3390 4060);
PAINT MONO (-3390 4060);
DISPLAY INVISIBLE (-3390 4060);
FORCEPROP 1 LASTPIN (-3400 4050) BN 1
J 0
(-3412 4058);
DISPLAY 0.489362 (-3412 4058);
PAINT GREEN (-3412 4058);
FORCEPROP 2 LAST CDS_LIB mstr_standard
J 0
(-3350 4050);
DISPLAY 0.723404 (-3350 4050);
PAINT MONO (-3350 4050);
DISPLAY INVISIBLE (-3350 4050);
FORCEPROP 1 LAST BODY_TYPE PLUMBING
J 0
(-3350 4100);
DISPLAY 0.872340 (-3350 4100);
PAINT GREEN (-3350 4100);
DISPLAY INVISIBLE (-3350 4100);
FORCEPROP 1 LAST HDL_TAP TRUE
J 0
(-3025 3925);
DISPLAY 0.872340 (-3025 3925);
DISPLAY INVISIBLE (-3025 3925);
FORCEPROP 1 LAST PATH I197
J 0
(-3352 4050);
DISPLAY 0.872340 (-3352 4050);
PAINT GREEN (-3352 4050);
DISPLAY INVISIBLE (-3352 4050);
FORCEADD TAP..1
(-3350 3950);
FORCEPROP 3 LASTPIN (-3400 3950) SIG_NAME M_H_CPU1_SB_DQ<3>
J 0
(-3390 3960);
DISPLAY 0.659574 (-3390 3960);
PAINT MONO (-3390 3960);
DISPLAY INVISIBLE (-3390 3960);
FORCEPROP 1 LASTPIN (-3400 3950) BN 3
J 0
(-3412 3958);
DISPLAY 0.489362 (-3412 3958);
PAINT GREEN (-3412 3958);
FORCEPROP 2 LAST CDS_LIB mstr_standard
J 0
(-3350 3950);
DISPLAY 0.723404 (-3350 3950);
PAINT MONO (-3350 3950);
DISPLAY INVISIBLE (-3350 3950);
FORCEPROP 1 LAST BODY_TYPE PLUMBING
J 0
(-3350 4000);
DISPLAY 0.872340 (-3350 4000);
PAINT GREEN (-3350 4000);
DISPLAY INVISIBLE (-3350 4000);
FORCEPROP 1 LAST HDL_TAP TRUE
J 0
(-3025 3825);
DISPLAY 0.872340 (-3025 3825);
DISPLAY INVISIBLE (-3025 3825);
FORCEPROP 1 LAST PATH I198
J 0
(-3352 3950);
DISPLAY 0.872340 (-3352 3950);
PAINT GREEN (-3352 3950);
DISPLAY INVISIBLE (-3352 3950);
FORCEADD TAP..1
(-3350 3900);
FORCEPROP 3 LASTPIN (-3400 3900) SIG_NAME M_H_CPU1_SB_DQ<4>
J 0
(-3390 3910);
DISPLAY 0.659574 (-3390 3910);
PAINT MONO (-3390 3910);
DISPLAY INVISIBLE (-3390 3910);
FORCEPROP 1 LASTPIN (-3400 3900) BN 4
J 0
(-3412 3908);
DISPLAY 0.489362 (-3412 3908);
PAINT GREEN (-3412 3908);
FORCEPROP 2 LAST CDS_LIB mstr_standard
J 0
(-3350 3900);
DISPLAY 0.723404 (-3350 3900);
PAINT MONO (-3350 3900);
DISPLAY INVISIBLE (-3350 3900);
FORCEPROP 1 LAST BODY_TYPE PLUMBING
J 0
(-3350 3950);
DISPLAY 0.872340 (-3350 3950);
PAINT GREEN (-3350 3950);
DISPLAY INVISIBLE (-3350 3950);
FORCEPROP 1 LAST HDL_TAP TRUE
J 0
(-3025 3775);
DISPLAY 0.872340 (-3025 3775);
DISPLAY INVISIBLE (-3025 3775);
FORCEPROP 1 LAST PATH I199
J 0
(-3352 3900);
DISPLAY 0.872340 (-3352 3900);
PAINT GREEN (-3352 3900);
DISPLAY INVISIBLE (-3352 3900);
FORCEADD TAP..1
(-3350 3850);
FORCEPROP 3 LASTPIN (-3400 3850) SIG_NAME M_H_CPU1_SB_DQ<5>
J 0
(-3390 3860);
DISPLAY 0.659574 (-3390 3860);
PAINT MONO (-3390 3860);
DISPLAY INVISIBLE (-3390 3860);
FORCEPROP 1 LASTPIN (-3400 3850) BN 5
J 0
(-3412 3858);
DISPLAY 0.489362 (-3412 3858);
PAINT GREEN (-3412 3858);
FORCEPROP 2 LAST CDS_LIB mstr_standard
J 0
(-3350 3850);
DISPLAY 0.723404 (-3350 3850);
PAINT MONO (-3350 3850);
DISPLAY INVISIBLE (-3350 3850);
FORCEPROP 1 LAST BODY_TYPE PLUMBING
J 0
(-3350 3900);
DISPLAY 0.872340 (-3350 3900);
PAINT GREEN (-3350 3900);
DISPLAY INVISIBLE (-3350 3900);
FORCEPROP 1 LAST HDL_TAP TRUE
J 0
(-3025 3725);
DISPLAY 0.872340 (-3025 3725);
DISPLAY INVISIBLE (-3025 3725);
FORCEPROP 1 LAST PATH I200
J 0
(-3352 3850);
DISPLAY 0.872340 (-3352 3850);
PAINT GREEN (-3352 3850);
DISPLAY INVISIBLE (-3352 3850);
FORCEADD TAP..1
(-3350 3750);
FORCEPROP 3 LASTPIN (-3400 3750) SIG_NAME M_H_CPU1_SB_DQ<7>
J 0
(-3390 3760);
DISPLAY 0.659574 (-3390 3760);
PAINT MONO (-3390 3760);
DISPLAY INVISIBLE (-3390 3760);
FORCEPROP 1 LASTPIN (-3400 3750) BN 7
J 0
(-3412 3758);
DISPLAY 0.489362 (-3412 3758);
PAINT GREEN (-3412 3758);
FORCEPROP 2 LAST CDS_LIB mstr_standard
J 0
(-3350 3750);
DISPLAY 0.723404 (-3350 3750);
PAINT MONO (-3350 3750);
DISPLAY INVISIBLE (-3350 3750);
FORCEPROP 1 LAST BODY_TYPE PLUMBING
J 0
(-3350 3800);
DISPLAY 0.872340 (-3350 3800);
PAINT GREEN (-3350 3800);
DISPLAY INVISIBLE (-3350 3800);
FORCEPROP 1 LAST HDL_TAP TRUE
J 0
(-3025 3625);
DISPLAY 0.872340 (-3025 3625);
DISPLAY INVISIBLE (-3025 3625);
FORCEPROP 1 LAST PATH I201
J 0
(-3352 3750);
DISPLAY 0.872340 (-3352 3750);
PAINT GREEN (-3352 3750);
DISPLAY INVISIBLE (-3352 3750);
FORCEADD TAP..1
(-3350 3650);
FORCEPROP 3 LASTPIN (-3400 3650) SIG_NAME M_H_CPU1_SB_DQ<8>
J 0
(-3390 3660);
DISPLAY 0.659574 (-3390 3660);
PAINT MONO (-3390 3660);
DISPLAY INVISIBLE (-3390 3660);
FORCEPROP 1 LASTPIN (-3400 3650) BN 8
J 0
(-3412 3658);
DISPLAY 0.489362 (-3412 3658);
PAINT GREEN (-3412 3658);
FORCEPROP 2 LAST CDS_LIB mstr_standard
J 0
(-3350 3650);
DISPLAY 0.723404 (-3350 3650);
PAINT MONO (-3350 3650);
DISPLAY INVISIBLE (-3350 3650);
FORCEPROP 1 LAST BODY_TYPE PLUMBING
J 0
(-3350 3700);
DISPLAY 0.872340 (-3350 3700);
PAINT GREEN (-3350 3700);
DISPLAY INVISIBLE (-3350 3700);
FORCEPROP 1 LAST HDL_TAP TRUE
J 0
(-3025 3525);
DISPLAY 0.872340 (-3025 3525);
DISPLAY INVISIBLE (-3025 3525);
FORCEPROP 1 LAST PATH I202
J 0
(-3352 3650);
DISPLAY 0.872340 (-3352 3650);
PAINT GREEN (-3352 3650);
DISPLAY INVISIBLE (-3352 3650);
FORCEADD TAP..1
(-3350 3800);
FORCEPROP 3 LASTPIN (-3400 3800) SIG_NAME M_H_CPU1_SB_DQ<6>
J 0
(-3390 3810);
DISPLAY 0.659574 (-3390 3810);
PAINT MONO (-3390 3810);
DISPLAY INVISIBLE (-3390 3810);
FORCEPROP 1 LASTPIN (-3400 3800) BN 6
J 0
(-3412 3808);
DISPLAY 0.489362 (-3412 3808);
PAINT GREEN (-3412 3808);
FORCEPROP 2 LAST CDS_LIB mstr_standard
J 0
(-3350 3800);
DISPLAY 0.723404 (-3350 3800);
PAINT MONO (-3350 3800);
DISPLAY INVISIBLE (-3350 3800);
FORCEPROP 1 LAST BODY_TYPE PLUMBING
J 0
(-3350 3850);
DISPLAY 0.872340 (-3350 3850);
PAINT GREEN (-3350 3850);
DISPLAY INVISIBLE (-3350 3850);
FORCEPROP 1 LAST HDL_TAP TRUE
J 0
(-3025 3675);
DISPLAY 0.872340 (-3025 3675);
DISPLAY INVISIBLE (-3025 3675);
FORCEPROP 1 LAST PATH I203
J 0
(-3352 3800);
DISPLAY 0.872340 (-3352 3800);
PAINT GREEN (-3352 3800);
DISPLAY INVISIBLE (-3352 3800);
FORCEADD TAP..1
(-3350 3600);
FORCEPROP 3 LASTPIN (-3400 3600) SIG_NAME M_H_CPU1_SB_DQ<9>
J 0
(-3390 3610);
DISPLAY 0.659574 (-3390 3610);
PAINT MONO (-3390 3610);
DISPLAY INVISIBLE (-3390 3610);
FORCEPROP 1 LASTPIN (-3400 3600) BN 9
J 0
(-3412 3608);
DISPLAY 0.489362 (-3412 3608);
PAINT GREEN (-3412 3608);
FORCEPROP 2 LAST CDS_LIB mstr_standard
J 0
(-3350 3600);
DISPLAY 0.723404 (-3350 3600);
PAINT MONO (-3350 3600);
DISPLAY INVISIBLE (-3350 3600);
FORCEPROP 1 LAST BODY_TYPE PLUMBING
J 0
(-3350 3650);
DISPLAY 0.872340 (-3350 3650);
PAINT GREEN (-3350 3650);
DISPLAY INVISIBLE (-3350 3650);
FORCEPROP 1 LAST HDL_TAP TRUE
J 0
(-3025 3475);
DISPLAY 0.872340 (-3025 3475);
DISPLAY INVISIBLE (-3025 3475);
FORCEPROP 1 LAST PATH I204
J 0
(-3352 3600);
DISPLAY 0.872340 (-3352 3600);
PAINT GREEN (-3352 3600);
DISPLAY INVISIBLE (-3352 3600);
FORCEADD TAP..1
(-3350 3550);
FORCEPROP 3 LASTPIN (-3400 3550) SIG_NAME M_H_CPU1_SB_DQ<10>
J 0
(-3390 3560);
DISPLAY 0.659574 (-3390 3560);
PAINT MONO (-3390 3560);
DISPLAY INVISIBLE (-3390 3560);
FORCEPROP 1 LASTPIN (-3400 3550) BN 10
J 0
(-3412 3558);
DISPLAY 0.489362 (-3412 3558);
PAINT GREEN (-3412 3558);
FORCEPROP 2 LAST CDS_LIB mstr_standard
J 0
(-3350 3550);
DISPLAY 0.723404 (-3350 3550);
PAINT MONO (-3350 3550);
DISPLAY INVISIBLE (-3350 3550);
FORCEPROP 1 LAST BODY_TYPE PLUMBING
J 0
(-3350 3600);
DISPLAY 0.872340 (-3350 3600);
PAINT GREEN (-3350 3600);
DISPLAY INVISIBLE (-3350 3600);
FORCEPROP 1 LAST HDL_TAP TRUE
J 0
(-3025 3425);
DISPLAY 0.872340 (-3025 3425);
DISPLAY INVISIBLE (-3025 3425);
FORCEPROP 1 LAST PATH I205
J 0
(-3352 3550);
DISPLAY 0.872340 (-3352 3550);
PAINT GREEN (-3352 3550);
DISPLAY INVISIBLE (-3352 3550);
FORCEADD TAP..1
(-3350 3500);
FORCEPROP 3 LASTPIN (-3400 3500) SIG_NAME M_H_CPU1_SB_DQ<11>
J 0
(-3390 3510);
DISPLAY 0.659574 (-3390 3510);
PAINT MONO (-3390 3510);
DISPLAY INVISIBLE (-3390 3510);
FORCEPROP 1 LASTPIN (-3400 3500) BN 11
J 0
(-3412 3508);
DISPLAY 0.489362 (-3412 3508);
PAINT GREEN (-3412 3508);
FORCEPROP 2 LAST CDS_LIB mstr_standard
J 0
(-3350 3500);
DISPLAY 0.723404 (-3350 3500);
PAINT MONO (-3350 3500);
DISPLAY INVISIBLE (-3350 3500);
FORCEPROP 1 LAST BODY_TYPE PLUMBING
J 0
(-3350 3550);
DISPLAY 0.872340 (-3350 3550);
PAINT GREEN (-3350 3550);
DISPLAY INVISIBLE (-3350 3550);
FORCEPROP 1 LAST HDL_TAP TRUE
J 0
(-3025 3375);
DISPLAY 0.872340 (-3025 3375);
DISPLAY INVISIBLE (-3025 3375);
FORCEPROP 1 LAST PATH I206
J 0
(-3352 3500);
DISPLAY 0.872340 (-3352 3500);
PAINT GREEN (-3352 3500);
DISPLAY INVISIBLE (-3352 3500);
FORCEADD TAP..1
(-3350 3350);
FORCEPROP 3 LASTPIN (-3400 3350) SIG_NAME M_H_CPU1_SB_DQ<14>
J 0
(-3390 3360);
DISPLAY 0.659574 (-3390 3360);
PAINT MONO (-3390 3360);
DISPLAY INVISIBLE (-3390 3360);
FORCEPROP 1 LASTPIN (-3400 3350) BN 14
J 0
(-3412 3358);
DISPLAY 0.489362 (-3412 3358);
PAINT GREEN (-3412 3358);
FORCEPROP 2 LAST CDS_LIB mstr_standard
J 0
(-3350 3350);
DISPLAY 0.723404 (-3350 3350);
PAINT MONO (-3350 3350);
DISPLAY INVISIBLE (-3350 3350);
FORCEPROP 1 LAST BODY_TYPE PLUMBING
J 0
(-3350 3400);
DISPLAY 0.872340 (-3350 3400);
PAINT GREEN (-3350 3400);
DISPLAY INVISIBLE (-3350 3400);
FORCEPROP 1 LAST HDL_TAP TRUE
J 0
(-3025 3225);
DISPLAY 0.872340 (-3025 3225);
DISPLAY INVISIBLE (-3025 3225);
FORCEPROP 1 LAST PATH I207
J 0
(-3352 3350);
DISPLAY 0.872340 (-3352 3350);
PAINT GREEN (-3352 3350);
DISPLAY INVISIBLE (-3352 3350);
FORCEADD TAP..1
(-3350 3400);
FORCEPROP 3 LASTPIN (-3400 3400) SIG_NAME M_H_CPU1_SB_DQ<13>
J 0
(-3390 3410);
DISPLAY 0.659574 (-3390 3410);
PAINT MONO (-3390 3410);
DISPLAY INVISIBLE (-3390 3410);
FORCEPROP 1 LASTPIN (-3400 3400) BN 13
J 0
(-3412 3408);
DISPLAY 0.489362 (-3412 3408);
PAINT GREEN (-3412 3408);
FORCEPROP 2 LAST CDS_LIB mstr_standard
J 0
(-3350 3400);
DISPLAY 0.723404 (-3350 3400);
PAINT MONO (-3350 3400);
DISPLAY INVISIBLE (-3350 3400);
FORCEPROP 1 LAST BODY_TYPE PLUMBING
J 0
(-3350 3450);
DISPLAY 0.872340 (-3350 3450);
PAINT GREEN (-3350 3450);
DISPLAY INVISIBLE (-3350 3450);
FORCEPROP 1 LAST HDL_TAP TRUE
J 0
(-3025 3275);
DISPLAY 0.872340 (-3025 3275);
DISPLAY INVISIBLE (-3025 3275);
FORCEPROP 1 LAST PATH I208
J 0
(-3352 3400);
DISPLAY 0.872340 (-3352 3400);
PAINT GREEN (-3352 3400);
DISPLAY INVISIBLE (-3352 3400);
FORCEADD TAP..1
(-3350 3450);
FORCEPROP 3 LASTPIN (-3400 3450) SIG_NAME M_H_CPU1_SB_DQ<12>
J 0
(-3390 3460);
DISPLAY 0.659574 (-3390 3460);
PAINT MONO (-3390 3460);
DISPLAY INVISIBLE (-3390 3460);
FORCEPROP 1 LASTPIN (-3400 3450) BN 12
J 0
(-3412 3458);
DISPLAY 0.489362 (-3412 3458);
PAINT GREEN (-3412 3458);
FORCEPROP 2 LAST CDS_LIB mstr_standard
J 0
(-3350 3450);
DISPLAY 0.723404 (-3350 3450);
PAINT MONO (-3350 3450);
DISPLAY INVISIBLE (-3350 3450);
FORCEPROP 1 LAST BODY_TYPE PLUMBING
J 0
(-3350 3500);
DISPLAY 0.872340 (-3350 3500);
PAINT GREEN (-3350 3500);
DISPLAY INVISIBLE (-3350 3500);
FORCEPROP 1 LAST HDL_TAP TRUE
J 0
(-3025 3325);
DISPLAY 0.872340 (-3025 3325);
DISPLAY INVISIBLE (-3025 3325);
FORCEPROP 1 LAST PATH I209
J 0
(-3352 3450);
DISPLAY 0.872340 (-3352 3450);
PAINT GREEN (-3352 3450);
DISPLAY INVISIBLE (-3352 3450);
FORCEADD TAP..1
(-3350 3150);
FORCEPROP 3 LASTPIN (-3400 3150) SIG_NAME M_H_CPU1_SB_DQ<17>
J 0
(-3390 3160);
DISPLAY 0.659574 (-3390 3160);
PAINT MONO (-3390 3160);
DISPLAY INVISIBLE (-3390 3160);
FORCEPROP 1 LASTPIN (-3400 3150) BN 17
J 0
(-3412 3158);
DISPLAY 0.489362 (-3412 3158);
PAINT GREEN (-3412 3158);
FORCEPROP 2 LAST CDS_LIB mstr_standard
J 0
(-3350 3150);
DISPLAY 0.723404 (-3350 3150);
PAINT MONO (-3350 3150);
DISPLAY INVISIBLE (-3350 3150);
FORCEPROP 1 LAST BODY_TYPE PLUMBING
J 0
(-3350 3200);
DISPLAY 0.872340 (-3350 3200);
PAINT GREEN (-3350 3200);
DISPLAY INVISIBLE (-3350 3200);
FORCEPROP 1 LAST HDL_TAP TRUE
J 0
(-3025 3025);
DISPLAY 0.872340 (-3025 3025);
DISPLAY INVISIBLE (-3025 3025);
FORCEPROP 1 LAST PATH I210
J 0
(-3352 3150);
DISPLAY 0.872340 (-3352 3150);
PAINT GREEN (-3352 3150);
DISPLAY INVISIBLE (-3352 3150);
FORCEADD TAP..1
(-3350 3200);
FORCEPROP 3 LASTPIN (-3400 3200) SIG_NAME M_H_CPU1_SB_DQ<16>
J 0
(-3390 3210);
DISPLAY 0.659574 (-3390 3210);
PAINT MONO (-3390 3210);
DISPLAY INVISIBLE (-3390 3210);
FORCEPROP 1 LASTPIN (-3400 3200) BN 16
J 0
(-3412 3208);
DISPLAY 0.489362 (-3412 3208);
PAINT GREEN (-3412 3208);
FORCEPROP 2 LAST CDS_LIB mstr_standard
J 0
(-3350 3200);
DISPLAY 0.723404 (-3350 3200);
PAINT MONO (-3350 3200);
DISPLAY INVISIBLE (-3350 3200);
FORCEPROP 1 LAST BODY_TYPE PLUMBING
J 0
(-3350 3250);
DISPLAY 0.872340 (-3350 3250);
PAINT GREEN (-3350 3250);
DISPLAY INVISIBLE (-3350 3250);
FORCEPROP 1 LAST HDL_TAP TRUE
J 0
(-3025 3075);
DISPLAY 0.872340 (-3025 3075);
DISPLAY INVISIBLE (-3025 3075);
FORCEPROP 1 LAST PATH I211
J 0
(-3352 3200);
DISPLAY 0.872340 (-3352 3200);
PAINT GREEN (-3352 3200);
DISPLAY INVISIBLE (-3352 3200);
FORCEADD TAP..1
(-3350 3300);
FORCEPROP 3 LASTPIN (-3400 3300) SIG_NAME M_H_CPU1_SB_DQ<15>
J 0
(-3390 3310);
DISPLAY 0.659574 (-3390 3310);
PAINT MONO (-3390 3310);
DISPLAY INVISIBLE (-3390 3310);
FORCEPROP 1 LASTPIN (-3400 3300) BN 15
J 0
(-3412 3308);
DISPLAY 0.489362 (-3412 3308);
PAINT GREEN (-3412 3308);
FORCEPROP 2 LAST CDS_LIB mstr_standard
J 0
(-3350 3300);
DISPLAY 0.723404 (-3350 3300);
PAINT MONO (-3350 3300);
DISPLAY INVISIBLE (-3350 3300);
FORCEPROP 1 LAST BODY_TYPE PLUMBING
J 0
(-3350 3350);
DISPLAY 0.872340 (-3350 3350);
PAINT GREEN (-3350 3350);
DISPLAY INVISIBLE (-3350 3350);
FORCEPROP 1 LAST HDL_TAP TRUE
J 0
(-3025 3175);
DISPLAY 0.872340 (-3025 3175);
DISPLAY INVISIBLE (-3025 3175);
FORCEPROP 1 LAST PATH I212
J 0
(-3352 3300);
DISPLAY 0.872340 (-3352 3300);
PAINT GREEN (-3352 3300);
DISPLAY INVISIBLE (-3352 3300);
FORCEADD TAP..1
(-3350 3100);
FORCEPROP 3 LASTPIN (-3400 3100) SIG_NAME M_H_CPU1_SB_DQ<18>
J 0
(-3390 3110);
DISPLAY 0.659574 (-3390 3110);
PAINT MONO (-3390 3110);
DISPLAY INVISIBLE (-3390 3110);
FORCEPROP 1 LASTPIN (-3400 3100) BN 18
J 0
(-3412 3108);
DISPLAY 0.489362 (-3412 3108);
PAINT GREEN (-3412 3108);
FORCEPROP 2 LAST CDS_LIB mstr_standard
J 0
(-3350 3100);
DISPLAY 0.723404 (-3350 3100);
PAINT MONO (-3350 3100);
DISPLAY INVISIBLE (-3350 3100);
FORCEPROP 1 LAST BODY_TYPE PLUMBING
J 0
(-3350 3150);
DISPLAY 0.872340 (-3350 3150);
PAINT GREEN (-3350 3150);
DISPLAY INVISIBLE (-3350 3150);
FORCEPROP 1 LAST HDL_TAP TRUE
J 0
(-3025 2975);
DISPLAY 0.872340 (-3025 2975);
DISPLAY INVISIBLE (-3025 2975);
FORCEPROP 1 LAST PATH I213
J 0
(-3352 3100);
DISPLAY 0.872340 (-3352 3100);
PAINT GREEN (-3352 3100);
DISPLAY INVISIBLE (-3352 3100);
FORCEADD TAP..1
(-3350 2950);
FORCEPROP 3 LASTPIN (-3400 2950) SIG_NAME M_H_CPU1_SB_DQ<21>
J 0
(-3390 2960);
DISPLAY 0.659574 (-3390 2960);
PAINT MONO (-3390 2960);
DISPLAY INVISIBLE (-3390 2960);
FORCEPROP 1 LASTPIN (-3400 2950) BN 21
J 0
(-3412 2958);
DISPLAY 0.489362 (-3412 2958);
PAINT GREEN (-3412 2958);
FORCEPROP 2 LAST CDS_LIB mstr_standard
J 0
(-3350 2950);
DISPLAY 0.723404 (-3350 2950);
PAINT MONO (-3350 2950);
DISPLAY INVISIBLE (-3350 2950);
FORCEPROP 1 LAST BODY_TYPE PLUMBING
J 0
(-3350 3000);
DISPLAY 0.872340 (-3350 3000);
PAINT GREEN (-3350 3000);
DISPLAY INVISIBLE (-3350 3000);
FORCEPROP 1 LAST HDL_TAP TRUE
J 0
(-3025 2825);
DISPLAY 0.872340 (-3025 2825);
DISPLAY INVISIBLE (-3025 2825);
FORCEPROP 1 LAST PATH I214
J 0
(-3352 2950);
DISPLAY 0.872340 (-3352 2950);
PAINT GREEN (-3352 2950);
DISPLAY INVISIBLE (-3352 2950);
FORCEADD TAP..1
(-3350 3050);
FORCEPROP 3 LASTPIN (-3400 3050) SIG_NAME M_H_CPU1_SB_DQ<19>
J 0
(-3390 3060);
DISPLAY 0.659574 (-3390 3060);
PAINT MONO (-3390 3060);
DISPLAY INVISIBLE (-3390 3060);
FORCEPROP 1 LASTPIN (-3400 3050) BN 19
J 0
(-3412 3058);
DISPLAY 0.489362 (-3412 3058);
PAINT GREEN (-3412 3058);
FORCEPROP 2 LAST CDS_LIB mstr_standard
J 0
(-3350 3050);
DISPLAY 0.723404 (-3350 3050);
PAINT MONO (-3350 3050);
DISPLAY INVISIBLE (-3350 3050);
FORCEPROP 1 LAST BODY_TYPE PLUMBING
J 0
(-3350 3100);
DISPLAY 0.872340 (-3350 3100);
PAINT GREEN (-3350 3100);
DISPLAY INVISIBLE (-3350 3100);
FORCEPROP 1 LAST HDL_TAP TRUE
J 0
(-3025 2925);
DISPLAY 0.872340 (-3025 2925);
DISPLAY INVISIBLE (-3025 2925);
FORCEPROP 1 LAST PATH I215
J 0
(-3352 3050);
DISPLAY 0.872340 (-3352 3050);
PAINT GREEN (-3352 3050);
DISPLAY INVISIBLE (-3352 3050);
FORCEADD TAP..1
(-3350 3000);
FORCEPROP 3 LASTPIN (-3400 3000) SIG_NAME M_H_CPU1_SB_DQ<20>
J 0
(-3390 3010);
DISPLAY 0.659574 (-3390 3010);
PAINT MONO (-3390 3010);
DISPLAY INVISIBLE (-3390 3010);
FORCEPROP 1 LASTPIN (-3400 3000) BN 20
J 0
(-3412 3008);
DISPLAY 0.489362 (-3412 3008);
PAINT GREEN (-3412 3008);
FORCEPROP 2 LAST CDS_LIB mstr_standard
J 0
(-3350 3000);
DISPLAY 0.723404 (-3350 3000);
PAINT MONO (-3350 3000);
DISPLAY INVISIBLE (-3350 3000);
FORCEPROP 1 LAST BODY_TYPE PLUMBING
J 0
(-3350 3050);
DISPLAY 0.872340 (-3350 3050);
PAINT GREEN (-3350 3050);
DISPLAY INVISIBLE (-3350 3050);
FORCEPROP 1 LAST HDL_TAP TRUE
J 0
(-3025 2875);
DISPLAY 0.872340 (-3025 2875);
DISPLAY INVISIBLE (-3025 2875);
FORCEPROP 1 LAST PATH I216
J 0
(-3352 3000);
DISPLAY 0.872340 (-3352 3000);
PAINT GREEN (-3352 3000);
DISPLAY INVISIBLE (-3352 3000);
FORCEADD TAP..1
(-3350 2850);
FORCEPROP 3 LASTPIN (-3400 2850) SIG_NAME M_H_CPU1_SB_DQ<23>
J 0
(-3390 2860);
DISPLAY 0.659574 (-3390 2860);
PAINT MONO (-3390 2860);
DISPLAY INVISIBLE (-3390 2860);
FORCEPROP 1 LASTPIN (-3400 2850) BN 23
J 0
(-3412 2858);
DISPLAY 0.489362 (-3412 2858);
PAINT GREEN (-3412 2858);
FORCEPROP 2 LAST CDS_LIB mstr_standard
J 0
(-3350 2850);
DISPLAY 0.723404 (-3350 2850);
PAINT MONO (-3350 2850);
DISPLAY INVISIBLE (-3350 2850);
FORCEPROP 1 LAST BODY_TYPE PLUMBING
J 0
(-3350 2900);
DISPLAY 0.872340 (-3350 2900);
PAINT GREEN (-3350 2900);
DISPLAY INVISIBLE (-3350 2900);
FORCEPROP 1 LAST HDL_TAP TRUE
J 0
(-3025 2725);
DISPLAY 0.872340 (-3025 2725);
DISPLAY INVISIBLE (-3025 2725);
FORCEPROP 1 LAST PATH I217
J 0
(-3352 2850);
DISPLAY 0.872340 (-3352 2850);
PAINT GREEN (-3352 2850);
DISPLAY INVISIBLE (-3352 2850);
FORCEADD TAP..1
(-3350 2900);
FORCEPROP 3 LASTPIN (-3400 2900) SIG_NAME M_H_CPU1_SB_DQ<22>
J 0
(-3390 2910);
DISPLAY 0.659574 (-3390 2910);
PAINT MONO (-3390 2910);
DISPLAY INVISIBLE (-3390 2910);
FORCEPROP 1 LASTPIN (-3400 2900) BN 22
J 0
(-3412 2908);
DISPLAY 0.489362 (-3412 2908);
PAINT GREEN (-3412 2908);
FORCEPROP 2 LAST CDS_LIB mstr_standard
J 0
(-3350 2900);
DISPLAY 0.723404 (-3350 2900);
PAINT MONO (-3350 2900);
DISPLAY INVISIBLE (-3350 2900);
FORCEPROP 1 LAST BODY_TYPE PLUMBING
J 0
(-3350 2950);
DISPLAY 0.872340 (-3350 2950);
PAINT GREEN (-3350 2950);
DISPLAY INVISIBLE (-3350 2950);
FORCEPROP 1 LAST HDL_TAP TRUE
J 0
(-3025 2775);
DISPLAY 0.872340 (-3025 2775);
DISPLAY INVISIBLE (-3025 2775);
FORCEPROP 1 LAST PATH I218
J 0
(-3352 2900);
DISPLAY 0.872340 (-3352 2900);
PAINT GREEN (-3352 2900);
DISPLAY INVISIBLE (-3352 2900);
FORCEADD TAP..1
(-3350 2650);
FORCEPROP 3 LASTPIN (-3400 2650) SIG_NAME M_H_CPU1_SB_DQ<26>
J 0
(-3390 2660);
DISPLAY 0.659574 (-3390 2660);
PAINT MONO (-3390 2660);
DISPLAY INVISIBLE (-3390 2660);
FORCEPROP 1 LASTPIN (-3400 2650) BN 26
J 0
(-3412 2658);
DISPLAY 0.489362 (-3412 2658);
PAINT GREEN (-3412 2658);
FORCEPROP 2 LAST CDS_LIB mstr_standard
J 0
(-3350 2650);
DISPLAY 0.723404 (-3350 2650);
PAINT MONO (-3350 2650);
DISPLAY INVISIBLE (-3350 2650);
FORCEPROP 1 LAST BODY_TYPE PLUMBING
J 0
(-3350 2700);
DISPLAY 0.872340 (-3350 2700);
PAINT GREEN (-3350 2700);
DISPLAY INVISIBLE (-3350 2700);
FORCEPROP 1 LAST HDL_TAP TRUE
J 0
(-3025 2525);
DISPLAY 0.872340 (-3025 2525);
DISPLAY INVISIBLE (-3025 2525);
FORCEPROP 1 LAST PATH I219
J 0
(-3352 2650);
DISPLAY 0.872340 (-3352 2650);
PAINT GREEN (-3352 2650);
DISPLAY INVISIBLE (-3352 2650);
FORCEADD TAP..1
(-3350 2700);
FORCEPROP 3 LASTPIN (-3400 2700) SIG_NAME M_H_CPU1_SB_DQ<25>
J 0
(-3390 2710);
DISPLAY 0.659574 (-3390 2710);
PAINT MONO (-3390 2710);
DISPLAY INVISIBLE (-3390 2710);
FORCEPROP 1 LASTPIN (-3400 2700) BN 25
J 0
(-3412 2708);
DISPLAY 0.489362 (-3412 2708);
PAINT GREEN (-3412 2708);
FORCEPROP 2 LAST CDS_LIB mstr_standard
J 0
(-3350 2700);
DISPLAY 0.723404 (-3350 2700);
PAINT MONO (-3350 2700);
DISPLAY INVISIBLE (-3350 2700);
FORCEPROP 1 LAST BODY_TYPE PLUMBING
J 0
(-3350 2750);
DISPLAY 0.872340 (-3350 2750);
PAINT GREEN (-3350 2750);
DISPLAY INVISIBLE (-3350 2750);
FORCEPROP 1 LAST HDL_TAP TRUE
J 0
(-3025 2575);
DISPLAY 0.872340 (-3025 2575);
DISPLAY INVISIBLE (-3025 2575);
FORCEPROP 1 LAST PATH I220
J 0
(-3352 2700);
DISPLAY 0.872340 (-3352 2700);
PAINT GREEN (-3352 2700);
DISPLAY INVISIBLE (-3352 2700);
FORCEADD TAP..1
(-3350 2750);
FORCEPROP 3 LASTPIN (-3400 2750) SIG_NAME M_H_CPU1_SB_DQ<24>
J 0
(-3390 2760);
DISPLAY 0.659574 (-3390 2760);
PAINT MONO (-3390 2760);
DISPLAY INVISIBLE (-3390 2760);
FORCEPROP 1 LASTPIN (-3400 2750) BN 24
J 0
(-3412 2758);
DISPLAY 0.489362 (-3412 2758);
PAINT GREEN (-3412 2758);
FORCEPROP 2 LAST CDS_LIB mstr_standard
J 0
(-3350 2750);
DISPLAY 0.723404 (-3350 2750);
PAINT MONO (-3350 2750);
DISPLAY INVISIBLE (-3350 2750);
FORCEPROP 1 LAST BODY_TYPE PLUMBING
J 0
(-3350 2800);
DISPLAY 0.872340 (-3350 2800);
PAINT GREEN (-3350 2800);
DISPLAY INVISIBLE (-3350 2800);
FORCEPROP 1 LAST HDL_TAP TRUE
J 0
(-3025 2625);
DISPLAY 0.872340 (-3025 2625);
DISPLAY INVISIBLE (-3025 2625);
FORCEPROP 1 LAST PATH I221
J 0
(-3352 2750);
DISPLAY 0.872340 (-3352 2750);
PAINT GREEN (-3352 2750);
DISPLAY INVISIBLE (-3352 2750);
FORCEADD TAP..1
(-3350 2600);
FORCEPROP 3 LASTPIN (-3400 2600) SIG_NAME M_H_CPU1_SB_DQ<27>
J 0
(-3390 2610);
DISPLAY 0.659574 (-3390 2610);
PAINT MONO (-3390 2610);
DISPLAY INVISIBLE (-3390 2610);
FORCEPROP 1 LASTPIN (-3400 2600) BN 27
J 0
(-3412 2608);
DISPLAY 0.489362 (-3412 2608);
PAINT GREEN (-3412 2608);
FORCEPROP 2 LAST CDS_LIB mstr_standard
J 0
(-3350 2600);
DISPLAY 0.723404 (-3350 2600);
PAINT MONO (-3350 2600);
DISPLAY INVISIBLE (-3350 2600);
FORCEPROP 1 LAST BODY_TYPE PLUMBING
J 0
(-3350 2650);
DISPLAY 0.872340 (-3350 2650);
PAINT GREEN (-3350 2650);
DISPLAY INVISIBLE (-3350 2650);
FORCEPROP 1 LAST HDL_TAP TRUE
J 0
(-3025 2475);
DISPLAY 0.872340 (-3025 2475);
DISPLAY INVISIBLE (-3025 2475);
FORCEPROP 1 LAST PATH I222
J 0
(-3352 2600);
DISPLAY 0.872340 (-3352 2600);
PAINT GREEN (-3352 2600);
DISPLAY INVISIBLE (-3352 2600);
FORCEADD TAP..1
(-3350 2400);
FORCEPROP 3 LASTPIN (-3400 2400) SIG_NAME M_H_CPU1_SB_DQ<31>
J 0
(-3390 2410);
DISPLAY 0.659574 (-3390 2410);
PAINT MONO (-3390 2410);
DISPLAY INVISIBLE (-3390 2410);
FORCEPROP 1 LASTPIN (-3400 2400) BN 31
J 0
(-3412 2408);
DISPLAY 0.489362 (-3412 2408);
PAINT GREEN (-3412 2408);
FORCEPROP 2 LAST CDS_LIB mstr_standard
J 0
(-3350 2400);
DISPLAY 0.723404 (-3350 2400);
PAINT MONO (-3350 2400);
DISPLAY INVISIBLE (-3350 2400);
FORCEPROP 1 LAST BODY_TYPE PLUMBING
J 0
(-3350 2450);
DISPLAY 0.872340 (-3350 2450);
PAINT GREEN (-3350 2450);
DISPLAY INVISIBLE (-3350 2450);
FORCEPROP 1 LAST HDL_TAP TRUE
J 0
(-3025 2275);
DISPLAY 0.872340 (-3025 2275);
DISPLAY INVISIBLE (-3025 2275);
FORCEPROP 1 LAST PATH I223
J 0
(-3352 2400);
DISPLAY 0.872340 (-3352 2400);
PAINT GREEN (-3352 2400);
DISPLAY INVISIBLE (-3352 2400);
FORCEADD TAP..1
(-3350 2550);
FORCEPROP 3 LASTPIN (-3400 2550) SIG_NAME M_H_CPU1_SB_DQ<28>
J 0
(-3390 2560);
DISPLAY 0.659574 (-3390 2560);
PAINT MONO (-3390 2560);
DISPLAY INVISIBLE (-3390 2560);
FORCEPROP 1 LASTPIN (-3400 2550) BN 28
J 0
(-3412 2558);
DISPLAY 0.489362 (-3412 2558);
PAINT GREEN (-3412 2558);
FORCEPROP 2 LAST CDS_LIB mstr_standard
J 0
(-3350 2550);
DISPLAY 0.723404 (-3350 2550);
PAINT MONO (-3350 2550);
DISPLAY INVISIBLE (-3350 2550);
FORCEPROP 1 LAST BODY_TYPE PLUMBING
J 0
(-3350 2600);
DISPLAY 0.872340 (-3350 2600);
PAINT GREEN (-3350 2600);
DISPLAY INVISIBLE (-3350 2600);
FORCEPROP 1 LAST HDL_TAP TRUE
J 0
(-3025 2425);
DISPLAY 0.872340 (-3025 2425);
DISPLAY INVISIBLE (-3025 2425);
FORCEPROP 1 LAST PATH I224
J 0
(-3352 2550);
DISPLAY 0.872340 (-3352 2550);
PAINT GREEN (-3352 2550);
DISPLAY INVISIBLE (-3352 2550);
FORCEADD TAP..1
(-3350 2500);
FORCEPROP 3 LASTPIN (-3400 2500) SIG_NAME M_H_CPU1_SB_DQ<29>
J 0
(-3390 2510);
DISPLAY 0.659574 (-3390 2510);
PAINT MONO (-3390 2510);
DISPLAY INVISIBLE (-3390 2510);
FORCEPROP 1 LASTPIN (-3400 2500) BN 29
J 0
(-3412 2508);
DISPLAY 0.489362 (-3412 2508);
PAINT GREEN (-3412 2508);
FORCEPROP 2 LAST CDS_LIB mstr_standard
J 0
(-3350 2500);
DISPLAY 0.723404 (-3350 2500);
PAINT MONO (-3350 2500);
DISPLAY INVISIBLE (-3350 2500);
FORCEPROP 1 LAST BODY_TYPE PLUMBING
J 0
(-3350 2550);
DISPLAY 0.872340 (-3350 2550);
PAINT GREEN (-3350 2550);
DISPLAY INVISIBLE (-3350 2550);
FORCEPROP 1 LAST HDL_TAP TRUE
J 0
(-3025 2375);
DISPLAY 0.872340 (-3025 2375);
DISPLAY INVISIBLE (-3025 2375);
FORCEPROP 1 LAST PATH I225
J 0
(-3352 2500);
DISPLAY 0.872340 (-3352 2500);
PAINT GREEN (-3352 2500);
DISPLAY INVISIBLE (-3352 2500);
FORCEADD TAP..1
(-3350 2450);
FORCEPROP 3 LASTPIN (-3400 2450) SIG_NAME M_H_CPU1_SB_DQ<30>
J 0
(-3390 2460);
DISPLAY 0.659574 (-3390 2460);
PAINT MONO (-3390 2460);
DISPLAY INVISIBLE (-3390 2460);
FORCEPROP 1 LASTPIN (-3400 2450) BN 30
J 0
(-3412 2458);
DISPLAY 0.489362 (-3412 2458);
PAINT GREEN (-3412 2458);
FORCEPROP 2 LAST CDS_LIB mstr_standard
J 0
(-3350 2450);
DISPLAY 0.723404 (-3350 2450);
PAINT MONO (-3350 2450);
DISPLAY INVISIBLE (-3350 2450);
FORCEPROP 1 LAST BODY_TYPE PLUMBING
J 0
(-3350 2500);
DISPLAY 0.872340 (-3350 2500);
PAINT GREEN (-3350 2500);
DISPLAY INVISIBLE (-3350 2500);
FORCEPROP 1 LAST HDL_TAP TRUE
J 0
(-3025 2325);
DISPLAY 0.872340 (-3025 2325);
DISPLAY INVISIBLE (-3025 2325);
FORCEPROP 1 LAST PATH I226
J 0
(-3352 2450);
DISPLAY 0.872340 (-3352 2450);
PAINT GREEN (-3352 2450);
DISPLAY INVISIBLE (-3352 2450);
FORCEADD TAP..1
(-3350 2250);
FORCEPROP 3 LASTPIN (-3400 2250) SIG_NAME M_H_CPU1_SA_CB<1>
J 0
(-3390 2260);
DISPLAY 0.659574 (-3390 2260);
PAINT MONO (-3390 2260);
DISPLAY INVISIBLE (-3390 2260);
FORCEPROP 1 LASTPIN (-3400 2250) BN 1
J 0
(-3412 2258);
DISPLAY 0.489362 (-3412 2258);
PAINT GREEN (-3412 2258);
FORCEPROP 2 LAST CDS_LIB mstr_standard
J 2
(-3350 2250);
DISPLAY 0.723404 (-3350 2250);
PAINT MONO (-3350 2250);
DISPLAY INVISIBLE (-3350 2250);
FORCEPROP 1 LAST BODY_TYPE PLUMBING
J 0
(-3350 2300);
DISPLAY 0.872340 (-3350 2300);
PAINT GREEN (-3350 2300);
DISPLAY INVISIBLE (-3350 2300);
FORCEPROP 1 LAST HDL_TAP TRUE
J 0
(-3025 2125);
DISPLAY 0.872340 (-3025 2125);
DISPLAY INVISIBLE (-3025 2125);
FORCEPROP 1 LAST PATH I227
J 0
(-3352 2250);
DISPLAY 0.872340 (-3352 2250);
PAINT GREEN (-3352 2250);
DISPLAY INVISIBLE (-3352 2250);
FORCEADD TAP..1
(-3350 2300);
FORCEPROP 3 LASTPIN (-3400 2300) SIG_NAME M_H_CPU1_SA_CB<0>
J 0
(-3390 2310);
DISPLAY 0.659574 (-3390 2310);
PAINT MONO (-3390 2310);
DISPLAY INVISIBLE (-3390 2310);
FORCEPROP 1 LASTPIN (-3400 2300) BN 0
J 0
(-3412 2308);
DISPLAY 0.489362 (-3412 2308);
PAINT GREEN (-3412 2308);
FORCEPROP 2 LAST CDS_LIB mstr_standard
J 2
(-3350 2300);
DISPLAY 0.723404 (-3350 2300);
PAINT MONO (-3350 2300);
DISPLAY INVISIBLE (-3350 2300);
FORCEPROP 1 LAST BODY_TYPE PLUMBING
J 0
(-3350 2350);
DISPLAY 0.872340 (-3350 2350);
PAINT GREEN (-3350 2350);
DISPLAY INVISIBLE (-3350 2350);
FORCEPROP 1 LAST HDL_TAP TRUE
J 0
(-3025 2175);
DISPLAY 0.872340 (-3025 2175);
DISPLAY INVISIBLE (-3025 2175);
FORCEPROP 1 LAST PATH I228
J 0
(-3352 2300);
DISPLAY 0.872340 (-3352 2300);
PAINT GREEN (-3352 2300);
DISPLAY INVISIBLE (-3352 2300);
FORCEADD TAP..1
(-3350 2200);
FORCEPROP 3 LASTPIN (-3400 2200) SIG_NAME M_H_CPU1_SA_CB<2>
J 0
(-3390 2210);
DISPLAY 0.659574 (-3390 2210);
PAINT MONO (-3390 2210);
DISPLAY INVISIBLE (-3390 2210);
FORCEPROP 1 LASTPIN (-3400 2200) BN 2
J 0
(-3412 2208);
DISPLAY 0.489362 (-3412 2208);
PAINT GREEN (-3412 2208);
FORCEPROP 2 LAST CDS_LIB mstr_standard
J 2
(-3350 2200);
DISPLAY 0.723404 (-3350 2200);
PAINT MONO (-3350 2200);
DISPLAY INVISIBLE (-3350 2200);
FORCEPROP 1 LAST BODY_TYPE PLUMBING
J 0
(-3350 2250);
DISPLAY 0.872340 (-3350 2250);
PAINT GREEN (-3350 2250);
DISPLAY INVISIBLE (-3350 2250);
FORCEPROP 1 LAST HDL_TAP TRUE
J 0
(-3025 2075);
DISPLAY 0.872340 (-3025 2075);
DISPLAY INVISIBLE (-3025 2075);
FORCEPROP 1 LAST PATH I229
J 0
(-3352 2200);
DISPLAY 0.872340 (-3352 2200);
PAINT GREEN (-3352 2200);
DISPLAY INVISIBLE (-3352 2200);
FORCEADD TAP..1
(-3350 2150);
FORCEPROP 3 LASTPIN (-3400 2150) SIG_NAME M_H_CPU1_SA_CB<3>
J 0
(-3390 2160);
DISPLAY 0.659574 (-3390 2160);
PAINT MONO (-3390 2160);
DISPLAY INVISIBLE (-3390 2160);
FORCEPROP 1 LASTPIN (-3400 2150) BN 3
J 0
(-3412 2158);
DISPLAY 0.489362 (-3412 2158);
PAINT GREEN (-3412 2158);
FORCEPROP 2 LAST CDS_LIB mstr_standard
J 2
(-3350 2150);
DISPLAY 0.723404 (-3350 2150);
PAINT MONO (-3350 2150);
DISPLAY INVISIBLE (-3350 2150);
FORCEPROP 1 LAST BODY_TYPE PLUMBING
J 0
(-3350 2200);
DISPLAY 0.872340 (-3350 2200);
PAINT GREEN (-3350 2200);
DISPLAY INVISIBLE (-3350 2200);
FORCEPROP 1 LAST HDL_TAP TRUE
J 0
(-3025 2025);
DISPLAY 0.872340 (-3025 2025);
DISPLAY INVISIBLE (-3025 2025);
FORCEPROP 1 LAST PATH I230
J 0
(-3352 2150);
DISPLAY 0.872340 (-3352 2150);
PAINT GREEN (-3352 2150);
DISPLAY INVISIBLE (-3352 2150);
FORCEADD TAP..1
(-3350 2050);
FORCEPROP 3 LASTPIN (-3400 2050) SIG_NAME M_H_CPU1_SA_CB<5>
J 0
(-3390 2060);
DISPLAY 0.659574 (-3390 2060);
PAINT MONO (-3390 2060);
DISPLAY INVISIBLE (-3390 2060);
FORCEPROP 1 LASTPIN (-3400 2050) BN 5
J 0
(-3412 2058);
DISPLAY 0.489362 (-3412 2058);
PAINT GREEN (-3412 2058);
FORCEPROP 2 LAST CDS_LIB mstr_standard
J 2
(-3350 2050);
DISPLAY 0.723404 (-3350 2050);
PAINT MONO (-3350 2050);
DISPLAY INVISIBLE (-3350 2050);
FORCEPROP 1 LAST BODY_TYPE PLUMBING
J 0
(-3350 2100);
DISPLAY 0.872340 (-3350 2100);
PAINT GREEN (-3350 2100);
DISPLAY INVISIBLE (-3350 2100);
FORCEPROP 1 LAST HDL_TAP TRUE
J 0
(-3025 1925);
DISPLAY 0.872340 (-3025 1925);
DISPLAY INVISIBLE (-3025 1925);
FORCEPROP 1 LAST PATH I231
J 0
(-3352 2050);
DISPLAY 0.872340 (-3352 2050);
PAINT GREEN (-3352 2050);
DISPLAY INVISIBLE (-3352 2050);
FORCEADD TAP..1
(-3350 2100);
FORCEPROP 3 LASTPIN (-3400 2100) SIG_NAME M_H_CPU1_SA_CB<4>
J 0
(-3390 2110);
DISPLAY 0.659574 (-3390 2110);
PAINT MONO (-3390 2110);
DISPLAY INVISIBLE (-3390 2110);
FORCEPROP 1 LASTPIN (-3400 2100) BN 4
J 0
(-3412 2108);
DISPLAY 0.489362 (-3412 2108);
PAINT GREEN (-3412 2108);
FORCEPROP 2 LAST CDS_LIB mstr_standard
J 2
(-3350 2100);
DISPLAY 0.723404 (-3350 2100);
PAINT MONO (-3350 2100);
DISPLAY INVISIBLE (-3350 2100);
FORCEPROP 1 LAST BODY_TYPE PLUMBING
J 0
(-3350 2150);
DISPLAY 0.872340 (-3350 2150);
PAINT GREEN (-3350 2150);
DISPLAY INVISIBLE (-3350 2150);
FORCEPROP 1 LAST HDL_TAP TRUE
J 0
(-3025 1975);
DISPLAY 0.872340 (-3025 1975);
DISPLAY INVISIBLE (-3025 1975);
FORCEPROP 1 LAST PATH I232
J 0
(-3352 2100);
DISPLAY 0.872340 (-3352 2100);
PAINT GREEN (-3352 2100);
DISPLAY INVISIBLE (-3352 2100);
FORCEADD OFFPAGE..6
R 2
(-2750 1900);
FORCEPROP 2 LAST $XR0 104 
J 0
(-2536 1900);
DISPLAY 0.638298 (-2536 1900);
PAINT MONO (-2536 1900);
FORCEPROP 2 LAST PATH I233
J 0
(-2525 1950);
DISPLAY 1.021277 (-2525 1950);
DISPLAY INVISIBLE (-2525 1950);
FORCEPROP 1 LAST COMMENT_BODY TRUE
J 2
(-2850 1825);
DISPLAY 0.872340 (-2850 1825);
PAINT GREEN (-2850 1825);
DISPLAY INVISIBLE (-2850 1825);
FORCEPROP 1 LAST OFFPAGE TRUE
J 2
(-3075 1775);
DISPLAY 0.872340 (-3075 1775);
PAINT GREEN (-3075 1775);
DISPLAY INVISIBLE (-3075 1775);
FORCEPROP 2 LAST CDS_LIB mstr_standard
J 2
(-2750 1900);
DISPLAY 0.723404 (-2750 1900);
PAINT MONO (-2750 1900);
DISPLAY INVISIBLE (-2750 1900);
FORCEADD TAP..1
(-3350 1950);
FORCEPROP 3 LASTPIN (-3400 1950) SIG_NAME M_H_CPU1_SA_CB<7>
J 0
(-3390 1960);
DISPLAY 0.659574 (-3390 1960);
PAINT MONO (-3390 1960);
DISPLAY INVISIBLE (-3390 1960);
FORCEPROP 1 LASTPIN (-3400 1950) BN 7
J 0
(-3412 1958);
DISPLAY 0.489362 (-3412 1958);
PAINT GREEN (-3412 1958);
FORCEPROP 2 LAST CDS_LIB mstr_standard
J 2
(-3350 1950);
DISPLAY 0.723404 (-3350 1950);
PAINT MONO (-3350 1950);
DISPLAY INVISIBLE (-3350 1950);
FORCEPROP 1 LAST BODY_TYPE PLUMBING
J 0
(-3350 2000);
DISPLAY 0.872340 (-3350 2000);
PAINT GREEN (-3350 2000);
DISPLAY INVISIBLE (-3350 2000);
FORCEPROP 1 LAST HDL_TAP TRUE
J 0
(-3025 1825);
DISPLAY 0.872340 (-3025 1825);
DISPLAY INVISIBLE (-3025 1825);
FORCEPROP 1 LAST PATH I234
J 0
(-3352 1950);
DISPLAY 0.872340 (-3352 1950);
PAINT GREEN (-3352 1950);
DISPLAY INVISIBLE (-3352 1950);
FORCEADD TAP..1
(-3350 1850);
FORCEPROP 3 LASTPIN (-3400 1850) SIG_NAME M_H_CPU1_SB_CB<0>
J 0
(-3390 1860);
DISPLAY 0.659574 (-3390 1860);
PAINT MONO (-3390 1860);
DISPLAY INVISIBLE (-3390 1860);
FORCEPROP 1 LASTPIN (-3400 1850) BN 0
J 0
(-3412 1858);
DISPLAY 0.489362 (-3412 1858);
PAINT GREEN (-3412 1858);
FORCEPROP 2 LAST CDS_LIB mstr_standard
J 2
(-3350 1850);
DISPLAY 0.723404 (-3350 1850);
PAINT MONO (-3350 1850);
DISPLAY INVISIBLE (-3350 1850);
FORCEPROP 1 LAST BODY_TYPE PLUMBING
J 0
(-3350 1900);
DISPLAY 0.872340 (-3350 1900);
PAINT GREEN (-3350 1900);
DISPLAY INVISIBLE (-3350 1900);
FORCEPROP 1 LAST HDL_TAP TRUE
J 0
(-3025 1725);
DISPLAY 0.872340 (-3025 1725);
DISPLAY INVISIBLE (-3025 1725);
FORCEPROP 1 LAST PATH I235
J 0
(-3352 1850);
DISPLAY 0.872340 (-3352 1850);
PAINT GREEN (-3352 1850);
DISPLAY INVISIBLE (-3352 1850);
FORCEADD TAP..1
(-3350 2000);
FORCEPROP 3 LASTPIN (-3400 2000) SIG_NAME M_H_CPU1_SA_CB<6>
J 0
(-3390 2010);
DISPLAY 0.659574 (-3390 2010);
PAINT MONO (-3390 2010);
DISPLAY INVISIBLE (-3390 2010);
FORCEPROP 1 LASTPIN (-3400 2000) BN 6
J 0
(-3412 2008);
DISPLAY 0.489362 (-3412 2008);
PAINT GREEN (-3412 2008);
FORCEPROP 2 LAST CDS_LIB mstr_standard
J 2
(-3350 2000);
DISPLAY 0.723404 (-3350 2000);
PAINT MONO (-3350 2000);
DISPLAY INVISIBLE (-3350 2000);
FORCEPROP 1 LAST BODY_TYPE PLUMBING
J 0
(-3350 2050);
DISPLAY 0.872340 (-3350 2050);
PAINT GREEN (-3350 2050);
DISPLAY INVISIBLE (-3350 2050);
FORCEPROP 1 LAST HDL_TAP TRUE
J 0
(-3025 1875);
DISPLAY 0.872340 (-3025 1875);
DISPLAY INVISIBLE (-3025 1875);
FORCEPROP 1 LAST PATH I236
J 0
(-3352 2000);
DISPLAY 0.872340 (-3352 2000);
PAINT GREEN (-3352 2000);
DISPLAY INVISIBLE (-3352 2000);
FORCEADD TAP..1
(-3350 1800);
FORCEPROP 3 LASTPIN (-3400 1800) SIG_NAME M_H_CPU1_SB_CB<1>
J 0
(-3390 1810);
DISPLAY 0.659574 (-3390 1810);
PAINT MONO (-3390 1810);
DISPLAY INVISIBLE (-3390 1810);
FORCEPROP 1 LASTPIN (-3400 1800) BN 1
J 0
(-3412 1808);
DISPLAY 0.489362 (-3412 1808);
PAINT GREEN (-3412 1808);
FORCEPROP 2 LAST CDS_LIB mstr_standard
J 2
(-3350 1800);
DISPLAY 0.723404 (-3350 1800);
PAINT MONO (-3350 1800);
DISPLAY INVISIBLE (-3350 1800);
FORCEPROP 1 LAST BODY_TYPE PLUMBING
J 0
(-3350 1850);
DISPLAY 0.872340 (-3350 1850);
PAINT GREEN (-3350 1850);
DISPLAY INVISIBLE (-3350 1850);
FORCEPROP 1 LAST HDL_TAP TRUE
J 0
(-3025 1675);
DISPLAY 0.872340 (-3025 1675);
DISPLAY INVISIBLE (-3025 1675);
FORCEPROP 1 LAST PATH I237
J 0
(-3352 1800);
DISPLAY 0.872340 (-3352 1800);
PAINT GREEN (-3352 1800);
DISPLAY INVISIBLE (-3352 1800);
FORCEADD TAP..1
(-3350 1750);
FORCEPROP 3 LASTPIN (-3400 1750) SIG_NAME M_H_CPU1_SB_CB<2>
J 0
(-3390 1760);
DISPLAY 0.659574 (-3390 1760);
PAINT MONO (-3390 1760);
DISPLAY INVISIBLE (-3390 1760);
FORCEPROP 1 LASTPIN (-3400 1750) BN 2
J 0
(-3412 1758);
DISPLAY 0.489362 (-3412 1758);
PAINT GREEN (-3412 1758);
FORCEPROP 2 LAST CDS_LIB mstr_standard
J 2
(-3350 1750);
DISPLAY 0.723404 (-3350 1750);
PAINT MONO (-3350 1750);
DISPLAY INVISIBLE (-3350 1750);
FORCEPROP 1 LAST BODY_TYPE PLUMBING
J 0
(-3350 1800);
DISPLAY 0.872340 (-3350 1800);
PAINT GREEN (-3350 1800);
DISPLAY INVISIBLE (-3350 1800);
FORCEPROP 1 LAST HDL_TAP TRUE
J 0
(-3025 1625);
DISPLAY 0.872340 (-3025 1625);
DISPLAY INVISIBLE (-3025 1625);
FORCEPROP 1 LAST PATH I238
J 0
(-3352 1750);
DISPLAY 0.872340 (-3352 1750);
PAINT GREEN (-3352 1750);
DISPLAY INVISIBLE (-3352 1750);
FORCEADD TAP..1
(-3350 1700);
FORCEPROP 3 LASTPIN (-3400 1700) SIG_NAME M_H_CPU1_SB_CB<3>
J 0
(-3390 1710);
DISPLAY 0.659574 (-3390 1710);
PAINT MONO (-3390 1710);
DISPLAY INVISIBLE (-3390 1710);
FORCEPROP 1 LASTPIN (-3400 1700) BN 3
J 0
(-3412 1708);
DISPLAY 0.489362 (-3412 1708);
PAINT GREEN (-3412 1708);
FORCEPROP 2 LAST CDS_LIB mstr_standard
J 2
(-3350 1700);
DISPLAY 0.723404 (-3350 1700);
PAINT MONO (-3350 1700);
DISPLAY INVISIBLE (-3350 1700);
FORCEPROP 1 LAST BODY_TYPE PLUMBING
J 0
(-3350 1750);
DISPLAY 0.872340 (-3350 1750);
PAINT GREEN (-3350 1750);
DISPLAY INVISIBLE (-3350 1750);
FORCEPROP 1 LAST HDL_TAP TRUE
J 0
(-3025 1575);
DISPLAY 0.872340 (-3025 1575);
DISPLAY INVISIBLE (-3025 1575);
FORCEPROP 1 LAST PATH I239
J 0
(-3352 1700);
DISPLAY 0.872340 (-3352 1700);
PAINT GREEN (-3352 1700);
DISPLAY INVISIBLE (-3352 1700);
FORCEADD TAP..1
(-3350 1600);
FORCEPROP 3 LASTPIN (-3400 1600) SIG_NAME M_H_CPU1_SB_CB<5>
J 0
(-3390 1610);
DISPLAY 0.659574 (-3390 1610);
PAINT MONO (-3390 1610);
DISPLAY INVISIBLE (-3390 1610);
FORCEPROP 1 LASTPIN (-3400 1600) BN 5
J 0
(-3412 1608);
DISPLAY 0.489362 (-3412 1608);
PAINT GREEN (-3412 1608);
FORCEPROP 2 LAST CDS_LIB mstr_standard
J 2
(-3350 1600);
DISPLAY 0.723404 (-3350 1600);
PAINT MONO (-3350 1600);
DISPLAY INVISIBLE (-3350 1600);
FORCEPROP 1 LAST BODY_TYPE PLUMBING
J 0
(-3350 1650);
DISPLAY 0.872340 (-3350 1650);
PAINT GREEN (-3350 1650);
DISPLAY INVISIBLE (-3350 1650);
FORCEPROP 1 LAST HDL_TAP TRUE
J 0
(-3025 1475);
DISPLAY 0.872340 (-3025 1475);
DISPLAY INVISIBLE (-3025 1475);
FORCEPROP 1 LAST PATH I240
J 0
(-3352 1600);
DISPLAY 0.872340 (-3352 1600);
PAINT GREEN (-3352 1600);
DISPLAY INVISIBLE (-3352 1600);
FORCEADD TAP..1
(-3350 1550);
FORCEPROP 3 LASTPIN (-3400 1550) SIG_NAME M_H_CPU1_SB_CB<6>
J 0
(-3390 1560);
DISPLAY 0.659574 (-3390 1560);
PAINT MONO (-3390 1560);
DISPLAY INVISIBLE (-3390 1560);
FORCEPROP 1 LASTPIN (-3400 1550) BN 6
J 0
(-3412 1558);
DISPLAY 0.489362 (-3412 1558);
PAINT GREEN (-3412 1558);
FORCEPROP 2 LAST CDS_LIB mstr_standard
J 2
(-3350 1550);
DISPLAY 0.723404 (-3350 1550);
PAINT MONO (-3350 1550);
DISPLAY INVISIBLE (-3350 1550);
FORCEPROP 1 LAST BODY_TYPE PLUMBING
J 0
(-3350 1600);
DISPLAY 0.872340 (-3350 1600);
PAINT GREEN (-3350 1600);
DISPLAY INVISIBLE (-3350 1600);
FORCEPROP 1 LAST HDL_TAP TRUE
J 0
(-3025 1425);
DISPLAY 0.872340 (-3025 1425);
DISPLAY INVISIBLE (-3025 1425);
FORCEPROP 1 LAST PATH I241
J 0
(-3352 1550);
DISPLAY 0.872340 (-3352 1550);
PAINT GREEN (-3352 1550);
DISPLAY INVISIBLE (-3352 1550);
FORCEADD TAP..1
(-3350 1650);
FORCEPROP 3 LASTPIN (-3400 1650) SIG_NAME M_H_CPU1_SB_CB<4>
J 0
(-3390 1660);
DISPLAY 0.659574 (-3390 1660);
PAINT MONO (-3390 1660);
DISPLAY INVISIBLE (-3390 1660);
FORCEPROP 1 LASTPIN (-3400 1650) BN 4
J 0
(-3412 1658);
DISPLAY 0.489362 (-3412 1658);
PAINT GREEN (-3412 1658);
FORCEPROP 2 LAST CDS_LIB mstr_standard
J 2
(-3350 1650);
DISPLAY 0.723404 (-3350 1650);
PAINT MONO (-3350 1650);
DISPLAY INVISIBLE (-3350 1650);
FORCEPROP 1 LAST BODY_TYPE PLUMBING
J 0
(-3350 1700);
DISPLAY 0.872340 (-3350 1700);
PAINT GREEN (-3350 1700);
DISPLAY INVISIBLE (-3350 1700);
FORCEPROP 1 LAST HDL_TAP TRUE
J 0
(-3025 1525);
DISPLAY 0.872340 (-3025 1525);
DISPLAY INVISIBLE (-3025 1525);
FORCEPROP 1 LAST PATH I242
J 0
(-3352 1650);
DISPLAY 0.872340 (-3352 1650);
PAINT GREEN (-3352 1650);
DISPLAY INVISIBLE (-3352 1650);
FORCEADD TAP..1
(-3350 1500);
FORCEPROP 3 LASTPIN (-3400 1500) SIG_NAME M_H_CPU1_SB_CB<7>
J 0
(-3390 1510);
DISPLAY 0.659574 (-3390 1510);
PAINT MONO (-3390 1510);
DISPLAY INVISIBLE (-3390 1510);
FORCEPROP 1 LASTPIN (-3400 1500) BN 7
J 0
(-3412 1508);
DISPLAY 0.489362 (-3412 1508);
PAINT GREEN (-3412 1508);
FORCEPROP 2 LAST CDS_LIB mstr_standard
J 2
(-3350 1500);
DISPLAY 0.723404 (-3350 1500);
PAINT MONO (-3350 1500);
DISPLAY INVISIBLE (-3350 1500);
FORCEPROP 1 LAST BODY_TYPE PLUMBING
J 0
(-3350 1550);
DISPLAY 0.872340 (-3350 1550);
PAINT GREEN (-3350 1550);
DISPLAY INVISIBLE (-3350 1550);
FORCEPROP 1 LAST HDL_TAP TRUE
J 0
(-3025 1375);
DISPLAY 0.872340 (-3025 1375);
DISPLAY INVISIBLE (-3025 1375);
FORCEPROP 1 LAST PATH I243
J 0
(-3352 1500);
DISPLAY 0.872340 (-3352 1500);
PAINT GREEN (-3352 1500);
DISPLAY INVISIBLE (-3352 1500);
FORCEADD TAP..1
R 2
(-5775 5900);
FORCEPROP 3 LASTPIN (-5725 5900) SIG_NAME M_H_CPU1_SA_DQS_DP<0>
J 0
(-5715 5910);
DISPLAY 0.659574 (-5715 5910);
PAINT MONO (-5715 5910);
DISPLAY INVISIBLE (-5715 5910);
FORCEPROP 1 LASTPIN (-5725 5900) BN 0
J 2
(-5713 5908);
DISPLAY 0.489362 (-5713 5908);
PAINT GREEN (-5713 5908);
FORCEPROP 2 LAST CDS_LIB mstr_standard
J 2
(-5775 5900);
DISPLAY 0.723404 (-5775 5900);
PAINT MONO (-5775 5900);
DISPLAY INVISIBLE (-5775 5900);
FORCEPROP 1 LAST BODY_TYPE PLUMBING
J 2
(-5775 5950);
DISPLAY 0.872340 (-5775 5950);
PAINT GREEN (-5775 5950);
DISPLAY INVISIBLE (-5775 5950);
FORCEPROP 1 LAST HDL_TAP TRUE
J 2
(-6100 5775);
DISPLAY 0.872340 (-6100 5775);
DISPLAY INVISIBLE (-6100 5775);
FORCEPROP 1 LAST PATH I244
J 2
(-5773 5900);
DISPLAY 0.872340 (-5773 5900);
PAINT GREEN (-5773 5900);
DISPLAY INVISIBLE (-5773 5900);
FORCEADD TAP..1
R 2
(-5775 5800);
FORCEPROP 3 LASTPIN (-5725 5800) SIG_NAME M_H_CPU1_SA_DQS_DP<1>
J 0
(-5715 5810);
DISPLAY 0.659574 (-5715 5810);
PAINT MONO (-5715 5810);
DISPLAY INVISIBLE (-5715 5810);
FORCEPROP 1 LASTPIN (-5725 5800) BN 1
J 2
(-5713 5808);
DISPLAY 0.489362 (-5713 5808);
PAINT GREEN (-5713 5808);
FORCEPROP 2 LAST CDS_LIB mstr_standard
J 2
(-5775 5800);
DISPLAY 0.723404 (-5775 5800);
PAINT MONO (-5775 5800);
DISPLAY INVISIBLE (-5775 5800);
FORCEPROP 1 LAST BODY_TYPE PLUMBING
J 2
(-5775 5850);
DISPLAY 0.872340 (-5775 5850);
PAINT GREEN (-5775 5850);
DISPLAY INVISIBLE (-5775 5850);
FORCEPROP 1 LAST HDL_TAP TRUE
J 2
(-6100 5675);
DISPLAY 0.872340 (-6100 5675);
DISPLAY INVISIBLE (-6100 5675);
FORCEPROP 1 LAST PATH I245
J 2
(-5773 5800);
DISPLAY 0.872340 (-5773 5800);
PAINT GREEN (-5773 5800);
DISPLAY INVISIBLE (-5773 5800);
FORCEADD TAP..1
R 2
(-5775 5700);
FORCEPROP 3 LASTPIN (-5725 5700) SIG_NAME M_H_CPU1_SA_DQS_DP<2>
J 0
(-5715 5710);
DISPLAY 0.659574 (-5715 5710);
PAINT MONO (-5715 5710);
DISPLAY INVISIBLE (-5715 5710);
FORCEPROP 1 LASTPIN (-5725 5700) BN 2
J 2
(-5713 5708);
DISPLAY 0.489362 (-5713 5708);
PAINT GREEN (-5713 5708);
FORCEPROP 2 LAST CDS_LIB mstr_standard
J 2
(-5775 5700);
DISPLAY 0.723404 (-5775 5700);
PAINT MONO (-5775 5700);
DISPLAY INVISIBLE (-5775 5700);
FORCEPROP 1 LAST BODY_TYPE PLUMBING
J 2
(-5775 5750);
DISPLAY 0.872340 (-5775 5750);
PAINT GREEN (-5775 5750);
DISPLAY INVISIBLE (-5775 5750);
FORCEPROP 1 LAST HDL_TAP TRUE
J 2
(-6100 5575);
DISPLAY 0.872340 (-6100 5575);
DISPLAY INVISIBLE (-6100 5575);
FORCEPROP 1 LAST PATH I246
J 2
(-5773 5700);
DISPLAY 0.872340 (-5773 5700);
PAINT GREEN (-5773 5700);
DISPLAY INVISIBLE (-5773 5700);
FORCEADD TAP..1
R 2
(-5975 5650);
FORCEPROP 3 LASTPIN (-5925 5650) SIG_NAME M_H_CPU1_SA_DQS_DN<2>
J 0
(-5915 5660);
DISPLAY 0.659574 (-5915 5660);
PAINT MONO (-5915 5660);
DISPLAY INVISIBLE (-5915 5660);
FORCEPROP 1 LASTPIN (-5925 5650) BN 2
J 2
(-5913 5658);
DISPLAY 0.489362 (-5913 5658);
PAINT GREEN (-5913 5658);
FORCEPROP 2 LAST CDS_LIB mstr_standard
J 2
(-5975 5650);
DISPLAY 0.723404 (-5975 5650);
PAINT MONO (-5975 5650);
DISPLAY INVISIBLE (-5975 5650);
FORCEPROP 1 LAST BODY_TYPE PLUMBING
J 2
(-5975 5700);
DISPLAY 0.872340 (-5975 5700);
PAINT GREEN (-5975 5700);
DISPLAY INVISIBLE (-5975 5700);
FORCEPROP 1 LAST HDL_TAP TRUE
J 2
(-6300 5525);
DISPLAY 0.872340 (-6300 5525);
DISPLAY INVISIBLE (-6300 5525);
FORCEPROP 1 LAST PATH I247
J 2
(-5973 5650);
DISPLAY 0.872340 (-5973 5650);
PAINT GREEN (-5973 5650);
DISPLAY INVISIBLE (-5973 5650);
FORCEADD TAP..1
R 2
(-5975 5750);
FORCEPROP 3 LASTPIN (-5925 5750) SIG_NAME M_H_CPU1_SA_DQS_DN<1>
J 0
(-5915 5760);
DISPLAY 0.659574 (-5915 5760);
PAINT MONO (-5915 5760);
DISPLAY INVISIBLE (-5915 5760);
FORCEPROP 1 LASTPIN (-5925 5750) BN 1
J 2
(-5913 5758);
DISPLAY 0.489362 (-5913 5758);
PAINT GREEN (-5913 5758);
FORCEPROP 2 LAST CDS_LIB mstr_standard
J 2
(-5975 5750);
DISPLAY 0.723404 (-5975 5750);
PAINT MONO (-5975 5750);
DISPLAY INVISIBLE (-5975 5750);
FORCEPROP 1 LAST BODY_TYPE PLUMBING
J 2
(-5975 5800);
DISPLAY 0.872340 (-5975 5800);
PAINT GREEN (-5975 5800);
DISPLAY INVISIBLE (-5975 5800);
FORCEPROP 1 LAST HDL_TAP TRUE
J 2
(-6300 5625);
DISPLAY 0.872340 (-6300 5625);
DISPLAY INVISIBLE (-6300 5625);
FORCEPROP 1 LAST PATH I248
J 2
(-5973 5750);
DISPLAY 0.872340 (-5973 5750);
PAINT GREEN (-5973 5750);
DISPLAY INVISIBLE (-5973 5750);
FORCEADD TAP..1
R 2
(-5975 5850);
FORCEPROP 3 LASTPIN (-5925 5850) SIG_NAME M_H_CPU1_SA_DQS_DN<0>
J 0
(-5915 5860);
DISPLAY 0.659574 (-5915 5860);
PAINT MONO (-5915 5860);
DISPLAY INVISIBLE (-5915 5860);
FORCEPROP 1 LASTPIN (-5925 5850) BN 0
J 2
(-5913 5858);
DISPLAY 0.489362 (-5913 5858);
PAINT GREEN (-5913 5858);
FORCEPROP 2 LAST CDS_LIB mstr_standard
J 2
(-5975 5850);
DISPLAY 0.723404 (-5975 5850);
PAINT MONO (-5975 5850);
DISPLAY INVISIBLE (-5975 5850);
FORCEPROP 1 LAST BODY_TYPE PLUMBING
J 2
(-5975 5900);
DISPLAY 0.872340 (-5975 5900);
PAINT GREEN (-5975 5900);
DISPLAY INVISIBLE (-5975 5900);
FORCEPROP 1 LAST HDL_TAP TRUE
J 2
(-6300 5725);
DISPLAY 0.872340 (-6300 5725);
DISPLAY INVISIBLE (-6300 5725);
FORCEPROP 1 LAST PATH I249
J 2
(-5973 5850);
DISPLAY 0.872340 (-5973 5850);
PAINT GREEN (-5973 5850);
DISPLAY INVISIBLE (-5973 5850);
FORCEADD TAP..1
R 2
(-5775 5600);
FORCEPROP 3 LASTPIN (-5725 5600) SIG_NAME M_H_CPU1_SA_DQS_DP<3>
J 0
(-5715 5610);
DISPLAY 0.659574 (-5715 5610);
PAINT MONO (-5715 5610);
DISPLAY INVISIBLE (-5715 5610);
FORCEPROP 1 LASTPIN (-5725 5600) BN 3
J 2
(-5713 5608);
DISPLAY 0.489362 (-5713 5608);
PAINT GREEN (-5713 5608);
FORCEPROP 2 LAST CDS_LIB mstr_standard
J 2
(-5775 5600);
DISPLAY 0.723404 (-5775 5600);
PAINT MONO (-5775 5600);
DISPLAY INVISIBLE (-5775 5600);
FORCEPROP 1 LAST BODY_TYPE PLUMBING
J 2
(-5775 5650);
DISPLAY 0.872340 (-5775 5650);
PAINT GREEN (-5775 5650);
DISPLAY INVISIBLE (-5775 5650);
FORCEPROP 1 LAST HDL_TAP TRUE
J 2
(-6100 5475);
DISPLAY 0.872340 (-6100 5475);
DISPLAY INVISIBLE (-6100 5475);
FORCEPROP 1 LAST PATH I250
J 2
(-5773 5600);
DISPLAY 0.872340 (-5773 5600);
PAINT GREEN (-5773 5600);
DISPLAY INVISIBLE (-5773 5600);
FORCEADD TAP..1
R 2
(-5775 5500);
FORCEPROP 3 LASTPIN (-5725 5500) SIG_NAME M_H_CPU1_SA_DQS_DP<4>
J 0
(-5715 5510);
DISPLAY 0.659574 (-5715 5510);
PAINT MONO (-5715 5510);
DISPLAY INVISIBLE (-5715 5510);
FORCEPROP 1 LASTPIN (-5725 5500) BN 4
J 2
(-5713 5508);
DISPLAY 0.489362 (-5713 5508);
PAINT GREEN (-5713 5508);
FORCEPROP 2 LAST CDS_LIB mstr_standard
J 2
(-5775 5500);
DISPLAY 0.723404 (-5775 5500);
PAINT MONO (-5775 5500);
DISPLAY INVISIBLE (-5775 5500);
FORCEPROP 1 LAST BODY_TYPE PLUMBING
J 2
(-5775 5550);
DISPLAY 0.872340 (-5775 5550);
PAINT GREEN (-5775 5550);
DISPLAY INVISIBLE (-5775 5550);
FORCEPROP 1 LAST HDL_TAP TRUE
J 2
(-6100 5375);
DISPLAY 0.872340 (-6100 5375);
DISPLAY INVISIBLE (-6100 5375);
FORCEPROP 1 LAST PATH I251
J 2
(-5773 5500);
DISPLAY 0.872340 (-5773 5500);
PAINT GREEN (-5773 5500);
DISPLAY INVISIBLE (-5773 5500);
FORCEADD TAP..1
R 2
(-5775 5400);
FORCEPROP 3 LASTPIN (-5725 5400) SIG_NAME M_H_CPU1_SA_DQS_DP<5>
J 0
(-5715 5410);
DISPLAY 0.659574 (-5715 5410);
PAINT MONO (-5715 5410);
DISPLAY INVISIBLE (-5715 5410);
FORCEPROP 1 LASTPIN (-5725 5400) BN 5
J 2
(-5713 5408);
DISPLAY 0.489362 (-5713 5408);
PAINT GREEN (-5713 5408);
FORCEPROP 2 LAST CDS_LIB mstr_standard
J 2
(-5775 5400);
DISPLAY 0.723404 (-5775 5400);
PAINT MONO (-5775 5400);
DISPLAY INVISIBLE (-5775 5400);
FORCEPROP 1 LAST BODY_TYPE PLUMBING
J 2
(-5775 5450);
DISPLAY 0.872340 (-5775 5450);
PAINT GREEN (-5775 5450);
DISPLAY INVISIBLE (-5775 5450);
FORCEPROP 1 LAST HDL_TAP TRUE
J 2
(-6100 5275);
DISPLAY 0.872340 (-6100 5275);
DISPLAY INVISIBLE (-6100 5275);
FORCEPROP 1 LAST PATH I252
J 2
(-5773 5400);
DISPLAY 0.872340 (-5773 5400);
PAINT GREEN (-5773 5400);
DISPLAY INVISIBLE (-5773 5400);
FORCEADD TAP..1
R 2
(-5775 5300);
FORCEPROP 3 LASTPIN (-5725 5300) SIG_NAME M_H_CPU1_SA_DQS_DP<6>
J 0
(-5715 5310);
DISPLAY 0.659574 (-5715 5310);
PAINT MONO (-5715 5310);
DISPLAY INVISIBLE (-5715 5310);
FORCEPROP 1 LASTPIN (-5725 5300) BN 6
J 2
(-5713 5308);
DISPLAY 0.489362 (-5713 5308);
PAINT GREEN (-5713 5308);
FORCEPROP 2 LAST CDS_LIB mstr_standard
J 2
(-5775 5300);
DISPLAY 0.723404 (-5775 5300);
PAINT MONO (-5775 5300);
DISPLAY INVISIBLE (-5775 5300);
FORCEPROP 1 LAST BODY_TYPE PLUMBING
J 2
(-5775 5350);
DISPLAY 0.872340 (-5775 5350);
PAINT GREEN (-5775 5350);
DISPLAY INVISIBLE (-5775 5350);
FORCEPROP 1 LAST HDL_TAP TRUE
J 2
(-6100 5175);
DISPLAY 0.872340 (-6100 5175);
DISPLAY INVISIBLE (-6100 5175);
FORCEPROP 1 LAST PATH I253
J 2
(-5773 5300);
DISPLAY 0.872340 (-5773 5300);
PAINT GREEN (-5773 5300);
DISPLAY INVISIBLE (-5773 5300);
FORCEADD TAP..1
R 2
(-5775 5200);
FORCEPROP 3 LASTPIN (-5725 5200) SIG_NAME M_H_CPU1_SA_DQS_DP<7>
J 0
(-5715 5210);
DISPLAY 0.659574 (-5715 5210);
PAINT MONO (-5715 5210);
DISPLAY INVISIBLE (-5715 5210);
FORCEPROP 1 LASTPIN (-5725 5200) BN 7
J 2
(-5713 5208);
DISPLAY 0.489362 (-5713 5208);
PAINT GREEN (-5713 5208);
FORCEPROP 2 LAST CDS_LIB mstr_standard
J 2
(-5775 5200);
DISPLAY 0.723404 (-5775 5200);
PAINT MONO (-5775 5200);
DISPLAY INVISIBLE (-5775 5200);
FORCEPROP 1 LAST BODY_TYPE PLUMBING
J 2
(-5775 5250);
DISPLAY 0.872340 (-5775 5250);
PAINT GREEN (-5775 5250);
DISPLAY INVISIBLE (-5775 5250);
FORCEPROP 1 LAST HDL_TAP TRUE
J 2
(-6100 5075);
DISPLAY 0.872340 (-6100 5075);
DISPLAY INVISIBLE (-6100 5075);
FORCEPROP 1 LAST PATH I254
J 2
(-5773 5200);
DISPLAY 0.872340 (-5773 5200);
PAINT GREEN (-5773 5200);
DISPLAY INVISIBLE (-5773 5200);
FORCEADD TAP..1
R 2
(-5975 5550);
FORCEPROP 3 LASTPIN (-5925 5550) SIG_NAME M_H_CPU1_SA_DQS_DN<3>
J 0
(-5915 5560);
DISPLAY 0.659574 (-5915 5560);
PAINT MONO (-5915 5560);
DISPLAY INVISIBLE (-5915 5560);
FORCEPROP 1 LASTPIN (-5925 5550) BN 3
J 2
(-5913 5558);
DISPLAY 0.489362 (-5913 5558);
PAINT GREEN (-5913 5558);
FORCEPROP 2 LAST CDS_LIB mstr_standard
J 2
(-5975 5550);
DISPLAY 0.723404 (-5975 5550);
PAINT MONO (-5975 5550);
DISPLAY INVISIBLE (-5975 5550);
FORCEPROP 1 LAST BODY_TYPE PLUMBING
J 2
(-5975 5600);
DISPLAY 0.872340 (-5975 5600);
PAINT GREEN (-5975 5600);
DISPLAY INVISIBLE (-5975 5600);
FORCEPROP 1 LAST HDL_TAP TRUE
J 2
(-6300 5425);
DISPLAY 0.872340 (-6300 5425);
DISPLAY INVISIBLE (-6300 5425);
FORCEPROP 1 LAST PATH I255
J 2
(-5973 5550);
DISPLAY 0.872340 (-5973 5550);
PAINT GREEN (-5973 5550);
DISPLAY INVISIBLE (-5973 5550);
FORCEADD TAP..1
R 2
(-5975 5450);
FORCEPROP 3 LASTPIN (-5925 5450) SIG_NAME M_H_CPU1_SA_DQS_DN<4>
J 0
(-5915 5460);
DISPLAY 0.659574 (-5915 5460);
PAINT MONO (-5915 5460);
DISPLAY INVISIBLE (-5915 5460);
FORCEPROP 1 LASTPIN (-5925 5450) BN 4
J 2
(-5913 5458);
DISPLAY 0.489362 (-5913 5458);
PAINT GREEN (-5913 5458);
FORCEPROP 2 LAST CDS_LIB mstr_standard
J 2
(-5975 5450);
DISPLAY 0.723404 (-5975 5450);
PAINT MONO (-5975 5450);
DISPLAY INVISIBLE (-5975 5450);
FORCEPROP 1 LAST BODY_TYPE PLUMBING
J 2
(-5975 5500);
DISPLAY 0.872340 (-5975 5500);
PAINT GREEN (-5975 5500);
DISPLAY INVISIBLE (-5975 5500);
FORCEPROP 1 LAST HDL_TAP TRUE
J 2
(-6300 5325);
DISPLAY 0.872340 (-6300 5325);
DISPLAY INVISIBLE (-6300 5325);
FORCEPROP 1 LAST PATH I256
J 2
(-5973 5450);
DISPLAY 0.872340 (-5973 5450);
PAINT GREEN (-5973 5450);
DISPLAY INVISIBLE (-5973 5450);
FORCEADD TAP..1
R 2
(-5975 5350);
FORCEPROP 3 LASTPIN (-5925 5350) SIG_NAME M_H_CPU1_SA_DQS_DN<5>
J 0
(-5915 5360);
DISPLAY 0.659574 (-5915 5360);
PAINT MONO (-5915 5360);
DISPLAY INVISIBLE (-5915 5360);
FORCEPROP 1 LASTPIN (-5925 5350) BN 5
J 2
(-5913 5358);
DISPLAY 0.489362 (-5913 5358);
PAINT GREEN (-5913 5358);
FORCEPROP 2 LAST CDS_LIB mstr_standard
J 2
(-5975 5350);
DISPLAY 0.723404 (-5975 5350);
PAINT MONO (-5975 5350);
DISPLAY INVISIBLE (-5975 5350);
FORCEPROP 1 LAST BODY_TYPE PLUMBING
J 2
(-5975 5400);
DISPLAY 0.872340 (-5975 5400);
PAINT GREEN (-5975 5400);
DISPLAY INVISIBLE (-5975 5400);
FORCEPROP 1 LAST HDL_TAP TRUE
J 2
(-6300 5225);
DISPLAY 0.872340 (-6300 5225);
DISPLAY INVISIBLE (-6300 5225);
FORCEPROP 1 LAST PATH I257
J 2
(-5973 5350);
DISPLAY 0.872340 (-5973 5350);
PAINT GREEN (-5973 5350);
DISPLAY INVISIBLE (-5973 5350);
FORCEADD TAP..1
R 2
(-5975 5250);
FORCEPROP 3 LASTPIN (-5925 5250) SIG_NAME M_H_CPU1_SA_DQS_DN<6>
J 0
(-5915 5260);
DISPLAY 0.659574 (-5915 5260);
PAINT MONO (-5915 5260);
DISPLAY INVISIBLE (-5915 5260);
FORCEPROP 1 LASTPIN (-5925 5250) BN 6
J 2
(-5913 5258);
DISPLAY 0.489362 (-5913 5258);
PAINT GREEN (-5913 5258);
FORCEPROP 2 LAST CDS_LIB mstr_standard
J 2
(-5975 5250);
DISPLAY 0.723404 (-5975 5250);
PAINT MONO (-5975 5250);
DISPLAY INVISIBLE (-5975 5250);
FORCEPROP 1 LAST BODY_TYPE PLUMBING
J 2
(-5975 5300);
DISPLAY 0.872340 (-5975 5300);
PAINT GREEN (-5975 5300);
DISPLAY INVISIBLE (-5975 5300);
FORCEPROP 1 LAST HDL_TAP TRUE
J 2
(-6300 5125);
DISPLAY 0.872340 (-6300 5125);
DISPLAY INVISIBLE (-6300 5125);
FORCEPROP 1 LAST PATH I258
J 2
(-5973 5250);
DISPLAY 0.872340 (-5973 5250);
PAINT GREEN (-5973 5250);
DISPLAY INVISIBLE (-5973 5250);
FORCEADD TAP..1
R 2
(-5975 5150);
FORCEPROP 3 LASTPIN (-5925 5150) SIG_NAME M_H_CPU1_SA_DQS_DN<7>
J 0
(-5915 5160);
DISPLAY 0.659574 (-5915 5160);
PAINT MONO (-5915 5160);
DISPLAY INVISIBLE (-5915 5160);
FORCEPROP 1 LASTPIN (-5925 5150) BN 7
J 2
(-5913 5158);
DISPLAY 0.489362 (-5913 5158);
PAINT GREEN (-5913 5158);
FORCEPROP 2 LAST CDS_LIB mstr_standard
J 2
(-5975 5150);
DISPLAY 0.723404 (-5975 5150);
PAINT MONO (-5975 5150);
DISPLAY INVISIBLE (-5975 5150);
FORCEPROP 1 LAST BODY_TYPE PLUMBING
J 2
(-5975 5200);
DISPLAY 0.872340 (-5975 5200);
PAINT GREEN (-5975 5200);
DISPLAY INVISIBLE (-5975 5200);
FORCEPROP 1 LAST HDL_TAP TRUE
J 2
(-6300 5025);
DISPLAY 0.872340 (-6300 5025);
DISPLAY INVISIBLE (-6300 5025);
FORCEPROP 1 LAST PATH I259
J 2
(-5973 5150);
DISPLAY 0.872340 (-5973 5150);
PAINT GREEN (-5973 5150);
DISPLAY INVISIBLE (-5973 5150);
FORCEADD TAP..1
R 2
(-5775 5100);
FORCEPROP 3 LASTPIN (-5725 5100) SIG_NAME M_H_CPU1_SA_DQS_DP<8>
J 0
(-5715 5110);
DISPLAY 0.659574 (-5715 5110);
PAINT MONO (-5715 5110);
DISPLAY INVISIBLE (-5715 5110);
FORCEPROP 1 LASTPIN (-5725 5100) BN 8
J 2
(-5713 5108);
DISPLAY 0.489362 (-5713 5108);
PAINT GREEN (-5713 5108);
FORCEPROP 2 LAST CDS_LIB mstr_standard
J 2
(-5775 5100);
DISPLAY 0.723404 (-5775 5100);
PAINT MONO (-5775 5100);
DISPLAY INVISIBLE (-5775 5100);
FORCEPROP 1 LAST BODY_TYPE PLUMBING
J 2
(-5775 5150);
DISPLAY 0.872340 (-5775 5150);
PAINT GREEN (-5775 5150);
DISPLAY INVISIBLE (-5775 5150);
FORCEPROP 1 LAST HDL_TAP TRUE
J 2
(-6100 4975);
DISPLAY 0.872340 (-6100 4975);
DISPLAY INVISIBLE (-6100 4975);
FORCEPROP 1 LAST PATH I260
J 2
(-5773 5100);
DISPLAY 0.872340 (-5773 5100);
PAINT GREEN (-5773 5100);
DISPLAY INVISIBLE (-5773 5100);
FORCEADD TAP..1
R 2
(-5775 5000);
FORCEPROP 3 LASTPIN (-5725 5000) SIG_NAME M_H_CPU1_SA_DQS_DP<9>
J 0
(-5715 5010);
DISPLAY 0.659574 (-5715 5010);
PAINT MONO (-5715 5010);
DISPLAY INVISIBLE (-5715 5010);
FORCEPROP 1 LASTPIN (-5725 5000) BN 9
J 2
(-5713 5008);
DISPLAY 0.489362 (-5713 5008);
PAINT GREEN (-5713 5008);
FORCEPROP 2 LAST CDS_LIB mstr_standard
J 2
(-5775 5000);
DISPLAY 0.723404 (-5775 5000);
PAINT MONO (-5775 5000);
DISPLAY INVISIBLE (-5775 5000);
FORCEPROP 1 LAST BODY_TYPE PLUMBING
J 2
(-5775 5050);
DISPLAY 0.872340 (-5775 5050);
PAINT GREEN (-5775 5050);
DISPLAY INVISIBLE (-5775 5050);
FORCEPROP 1 LAST HDL_TAP TRUE
J 2
(-6100 4875);
DISPLAY 0.872340 (-6100 4875);
DISPLAY INVISIBLE (-6100 4875);
FORCEPROP 1 LAST PATH I261
J 2
(-5773 5000);
DISPLAY 0.872340 (-5773 5000);
PAINT GREEN (-5773 5000);
DISPLAY INVISIBLE (-5773 5000);
FORCEADD TAP..1
R 2
(-5775 4850);
FORCEPROP 3 LASTPIN (-5725 4850) SIG_NAME M_H_CPU1_SB_DQS_DP<0>
J 0
(-5715 4860);
DISPLAY 0.659574 (-5715 4860);
PAINT MONO (-5715 4860);
DISPLAY INVISIBLE (-5715 4860);
FORCEPROP 1 LASTPIN (-5725 4850) BN 0
J 2
(-5713 4858);
DISPLAY 0.489362 (-5713 4858);
PAINT GREEN (-5713 4858);
FORCEPROP 2 LAST CDS_LIB mstr_standard
J 2
(-5775 4850);
DISPLAY 0.723404 (-5775 4850);
PAINT MONO (-5775 4850);
DISPLAY INVISIBLE (-5775 4850);
FORCEPROP 1 LAST BODY_TYPE PLUMBING
J 2
(-5775 4900);
DISPLAY 0.872340 (-5775 4900);
PAINT GREEN (-5775 4900);
DISPLAY INVISIBLE (-5775 4900);
FORCEPROP 1 LAST HDL_TAP TRUE
J 2
(-6100 4725);
DISPLAY 0.872340 (-6100 4725);
DISPLAY INVISIBLE (-6100 4725);
FORCEPROP 1 LAST PATH I262
J 2
(-5773 4850);
DISPLAY 0.872340 (-5773 4850);
PAINT GREEN (-5773 4850);
DISPLAY INVISIBLE (-5773 4850);
FORCEADD TAP..1
R 2
(-5775 4750);
FORCEPROP 3 LASTPIN (-5725 4750) SIG_NAME M_H_CPU1_SB_DQS_DP<1>
J 0
(-5715 4760);
DISPLAY 0.659574 (-5715 4760);
PAINT MONO (-5715 4760);
DISPLAY INVISIBLE (-5715 4760);
FORCEPROP 1 LASTPIN (-5725 4750) BN 1
J 2
(-5713 4758);
DISPLAY 0.489362 (-5713 4758);
PAINT GREEN (-5713 4758);
FORCEPROP 2 LAST CDS_LIB mstr_standard
J 2
(-5775 4750);
DISPLAY 0.723404 (-5775 4750);
PAINT MONO (-5775 4750);
DISPLAY INVISIBLE (-5775 4750);
FORCEPROP 1 LAST BODY_TYPE PLUMBING
J 2
(-5775 4800);
DISPLAY 0.872340 (-5775 4800);
PAINT GREEN (-5775 4800);
DISPLAY INVISIBLE (-5775 4800);
FORCEPROP 1 LAST HDL_TAP TRUE
J 2
(-6100 4625);
DISPLAY 0.872340 (-6100 4625);
DISPLAY INVISIBLE (-6100 4625);
FORCEPROP 1 LAST PATH I263
J 2
(-5773 4750);
DISPLAY 0.872340 (-5773 4750);
PAINT GREEN (-5773 4750);
DISPLAY INVISIBLE (-5773 4750);
FORCEADD TAP..1
R 2
(-5775 4650);
FORCEPROP 3 LASTPIN (-5725 4650) SIG_NAME M_H_CPU1_SB_DQS_DP<2>
J 0
(-5715 4660);
DISPLAY 0.659574 (-5715 4660);
PAINT MONO (-5715 4660);
DISPLAY INVISIBLE (-5715 4660);
FORCEPROP 1 LASTPIN (-5725 4650) BN 2
J 2
(-5713 4658);
DISPLAY 0.489362 (-5713 4658);
PAINT GREEN (-5713 4658);
FORCEPROP 2 LAST CDS_LIB mstr_standard
J 2
(-5775 4650);
DISPLAY 0.723404 (-5775 4650);
PAINT MONO (-5775 4650);
DISPLAY INVISIBLE (-5775 4650);
FORCEPROP 1 LAST BODY_TYPE PLUMBING
J 2
(-5775 4700);
DISPLAY 0.872340 (-5775 4700);
PAINT GREEN (-5775 4700);
DISPLAY INVISIBLE (-5775 4700);
FORCEPROP 1 LAST HDL_TAP TRUE
J 2
(-6100 4525);
DISPLAY 0.872340 (-6100 4525);
DISPLAY INVISIBLE (-6100 4525);
FORCEPROP 1 LAST PATH I264
J 2
(-5773 4650);
DISPLAY 0.872340 (-5773 4650);
PAINT GREEN (-5773 4650);
DISPLAY INVISIBLE (-5773 4650);
FORCEADD TAP..1
R 2
(-5975 5050);
FORCEPROP 3 LASTPIN (-5925 5050) SIG_NAME M_H_CPU1_SA_DQS_DN<8>
J 0
(-5915 5060);
DISPLAY 0.659574 (-5915 5060);
PAINT MONO (-5915 5060);
DISPLAY INVISIBLE (-5915 5060);
FORCEPROP 1 LASTPIN (-5925 5050) BN 8
J 2
(-5913 5058);
DISPLAY 0.489362 (-5913 5058);
PAINT GREEN (-5913 5058);
FORCEPROP 2 LAST CDS_LIB mstr_standard
J 2
(-5975 5050);
DISPLAY 0.723404 (-5975 5050);
PAINT MONO (-5975 5050);
DISPLAY INVISIBLE (-5975 5050);
FORCEPROP 1 LAST BODY_TYPE PLUMBING
J 2
(-5975 5100);
DISPLAY 0.872340 (-5975 5100);
PAINT GREEN (-5975 5100);
DISPLAY INVISIBLE (-5975 5100);
FORCEPROP 1 LAST HDL_TAP TRUE
J 2
(-6300 4925);
DISPLAY 0.872340 (-6300 4925);
DISPLAY INVISIBLE (-6300 4925);
FORCEPROP 1 LAST PATH I265
J 2
(-5973 5050);
DISPLAY 0.872340 (-5973 5050);
PAINT GREEN (-5973 5050);
DISPLAY INVISIBLE (-5973 5050);
FORCEADD TAP..1
R 2
(-5975 4950);
FORCEPROP 3 LASTPIN (-5925 4950) SIG_NAME M_H_CPU1_SA_DQS_DN<9>
J 0
(-5915 4960);
DISPLAY 0.659574 (-5915 4960);
PAINT MONO (-5915 4960);
DISPLAY INVISIBLE (-5915 4960);
FORCEPROP 1 LASTPIN (-5925 4950) BN 9
J 2
(-5913 4958);
DISPLAY 0.489362 (-5913 4958);
PAINT GREEN (-5913 4958);
FORCEPROP 2 LAST CDS_LIB mstr_standard
J 2
(-5975 4950);
DISPLAY 0.723404 (-5975 4950);
PAINT MONO (-5975 4950);
DISPLAY INVISIBLE (-5975 4950);
FORCEPROP 1 LAST BODY_TYPE PLUMBING
J 2
(-5975 5000);
DISPLAY 0.872340 (-5975 5000);
PAINT GREEN (-5975 5000);
DISPLAY INVISIBLE (-5975 5000);
FORCEPROP 1 LAST HDL_TAP TRUE
J 2
(-6300 4825);
DISPLAY 0.872340 (-6300 4825);
DISPLAY INVISIBLE (-6300 4825);
FORCEPROP 1 LAST PATH I266
J 2
(-5973 4950);
DISPLAY 0.872340 (-5973 4950);
PAINT GREEN (-5973 4950);
DISPLAY INVISIBLE (-5973 4950);
FORCEADD TAP..1
R 2
(-5975 4800);
FORCEPROP 3 LASTPIN (-5925 4800) SIG_NAME M_H_CPU1_SB_DQS_DN<0>
J 0
(-5915 4810);
DISPLAY 0.659574 (-5915 4810);
PAINT MONO (-5915 4810);
DISPLAY INVISIBLE (-5915 4810);
FORCEPROP 1 LASTPIN (-5925 4800) BN 0
J 2
(-5913 4808);
DISPLAY 0.489362 (-5913 4808);
PAINT GREEN (-5913 4808);
FORCEPROP 2 LAST CDS_LIB mstr_standard
J 2
(-5975 4800);
DISPLAY 0.723404 (-5975 4800);
PAINT MONO (-5975 4800);
DISPLAY INVISIBLE (-5975 4800);
FORCEPROP 1 LAST BODY_TYPE PLUMBING
J 2
(-5975 4850);
DISPLAY 0.872340 (-5975 4850);
PAINT GREEN (-5975 4850);
DISPLAY INVISIBLE (-5975 4850);
FORCEPROP 1 LAST HDL_TAP TRUE
J 2
(-6300 4675);
DISPLAY 0.872340 (-6300 4675);
DISPLAY INVISIBLE (-6300 4675);
FORCEPROP 1 LAST PATH I267
J 2
(-5973 4800);
DISPLAY 0.872340 (-5973 4800);
PAINT GREEN (-5973 4800);
DISPLAY INVISIBLE (-5973 4800);
FORCEADD TAP..1
R 2
(-5975 4700);
FORCEPROP 3 LASTPIN (-5925 4700) SIG_NAME M_H_CPU1_SB_DQS_DN<1>
J 0
(-5915 4710);
DISPLAY 0.659574 (-5915 4710);
PAINT MONO (-5915 4710);
DISPLAY INVISIBLE (-5915 4710);
FORCEPROP 1 LASTPIN (-5925 4700) BN 1
J 2
(-5913 4708);
DISPLAY 0.489362 (-5913 4708);
PAINT GREEN (-5913 4708);
FORCEPROP 2 LAST CDS_LIB mstr_standard
J 2
(-5975 4700);
DISPLAY 0.723404 (-5975 4700);
PAINT MONO (-5975 4700);
DISPLAY INVISIBLE (-5975 4700);
FORCEPROP 1 LAST BODY_TYPE PLUMBING
J 2
(-5975 4750);
DISPLAY 0.872340 (-5975 4750);
PAINT GREEN (-5975 4750);
DISPLAY INVISIBLE (-5975 4750);
FORCEPROP 1 LAST HDL_TAP TRUE
J 2
(-6300 4575);
DISPLAY 0.872340 (-6300 4575);
DISPLAY INVISIBLE (-6300 4575);
FORCEPROP 1 LAST PATH I268
J 2
(-5973 4700);
DISPLAY 0.872340 (-5973 4700);
PAINT GREEN (-5973 4700);
DISPLAY INVISIBLE (-5973 4700);
FORCEADD TAP..1
R 2
(-5775 4550);
FORCEPROP 3 LASTPIN (-5725 4550) SIG_NAME M_H_CPU1_SB_DQS_DP<3>
J 0
(-5715 4560);
DISPLAY 0.659574 (-5715 4560);
PAINT MONO (-5715 4560);
DISPLAY INVISIBLE (-5715 4560);
FORCEPROP 1 LASTPIN (-5725 4550) BN 3
J 2
(-5713 4558);
DISPLAY 0.489362 (-5713 4558);
PAINT GREEN (-5713 4558);
FORCEPROP 2 LAST CDS_LIB mstr_standard
J 2
(-5775 4550);
DISPLAY 0.723404 (-5775 4550);
PAINT MONO (-5775 4550);
DISPLAY INVISIBLE (-5775 4550);
FORCEPROP 1 LAST BODY_TYPE PLUMBING
J 2
(-5775 4600);
DISPLAY 0.872340 (-5775 4600);
PAINT GREEN (-5775 4600);
DISPLAY INVISIBLE (-5775 4600);
FORCEPROP 1 LAST HDL_TAP TRUE
J 2
(-6100 4425);
DISPLAY 0.872340 (-6100 4425);
DISPLAY INVISIBLE (-6100 4425);
FORCEPROP 1 LAST PATH I269
J 2
(-5773 4550);
DISPLAY 0.872340 (-5773 4550);
PAINT GREEN (-5773 4550);
DISPLAY INVISIBLE (-5773 4550);
FORCEADD TAP..1
R 2
(-5775 4450);
FORCEPROP 3 LASTPIN (-5725 4450) SIG_NAME M_H_CPU1_SB_DQS_DP<4>
J 0
(-5715 4460);
DISPLAY 0.659574 (-5715 4460);
PAINT MONO (-5715 4460);
DISPLAY INVISIBLE (-5715 4460);
FORCEPROP 1 LASTPIN (-5725 4450) BN 4
J 2
(-5713 4458);
DISPLAY 0.489362 (-5713 4458);
PAINT GREEN (-5713 4458);
FORCEPROP 2 LAST CDS_LIB mstr_standard
J 2
(-5775 4450);
DISPLAY 0.723404 (-5775 4450);
PAINT MONO (-5775 4450);
DISPLAY INVISIBLE (-5775 4450);
FORCEPROP 1 LAST BODY_TYPE PLUMBING
J 2
(-5775 4500);
DISPLAY 0.872340 (-5775 4500);
PAINT GREEN (-5775 4500);
DISPLAY INVISIBLE (-5775 4500);
FORCEPROP 1 LAST HDL_TAP TRUE
J 2
(-6100 4325);
DISPLAY 0.872340 (-6100 4325);
DISPLAY INVISIBLE (-6100 4325);
FORCEPROP 1 LAST PATH I270
J 2
(-5773 4450);
DISPLAY 0.872340 (-5773 4450);
PAINT GREEN (-5773 4450);
DISPLAY INVISIBLE (-5773 4450);
FORCEADD TAP..1
R 2
(-5975 4600);
FORCEPROP 3 LASTPIN (-5925 4600) SIG_NAME M_H_CPU1_SB_DQS_DN<2>
J 0
(-5915 4610);
DISPLAY 0.659574 (-5915 4610);
PAINT MONO (-5915 4610);
DISPLAY INVISIBLE (-5915 4610);
FORCEPROP 1 LASTPIN (-5925 4600) BN 2
J 2
(-5913 4608);
DISPLAY 0.489362 (-5913 4608);
PAINT GREEN (-5913 4608);
FORCEPROP 2 LAST CDS_LIB mstr_standard
J 2
(-5975 4600);
DISPLAY 0.723404 (-5975 4600);
PAINT MONO (-5975 4600);
DISPLAY INVISIBLE (-5975 4600);
FORCEPROP 1 LAST BODY_TYPE PLUMBING
J 2
(-5975 4650);
DISPLAY 0.872340 (-5975 4650);
PAINT GREEN (-5975 4650);
DISPLAY INVISIBLE (-5975 4650);
FORCEPROP 1 LAST HDL_TAP TRUE
J 2
(-6300 4475);
DISPLAY 0.872340 (-6300 4475);
DISPLAY INVISIBLE (-6300 4475);
FORCEPROP 1 LAST PATH I271
J 2
(-5973 4600);
DISPLAY 0.872340 (-5973 4600);
PAINT GREEN (-5973 4600);
DISPLAY INVISIBLE (-5973 4600);
FORCEADD TAP..1
R 2
(-5775 4350);
FORCEPROP 3 LASTPIN (-5725 4350) SIG_NAME M_H_CPU1_SB_DQS_DP<5>
J 0
(-5715 4360);
DISPLAY 0.659574 (-5715 4360);
PAINT MONO (-5715 4360);
DISPLAY INVISIBLE (-5715 4360);
FORCEPROP 1 LASTPIN (-5725 4350) BN 5
J 2
(-5713 4358);
DISPLAY 0.489362 (-5713 4358);
PAINT GREEN (-5713 4358);
FORCEPROP 2 LAST CDS_LIB mstr_standard
J 2
(-5775 4350);
DISPLAY 0.723404 (-5775 4350);
PAINT MONO (-5775 4350);
DISPLAY INVISIBLE (-5775 4350);
FORCEPROP 1 LAST BODY_TYPE PLUMBING
J 2
(-5775 4400);
DISPLAY 0.872340 (-5775 4400);
PAINT GREEN (-5775 4400);
DISPLAY INVISIBLE (-5775 4400);
FORCEPROP 1 LAST HDL_TAP TRUE
J 2
(-6100 4225);
DISPLAY 0.872340 (-6100 4225);
DISPLAY INVISIBLE (-6100 4225);
FORCEPROP 1 LAST PATH I272
J 2
(-5773 4350);
DISPLAY 0.872340 (-5773 4350);
PAINT GREEN (-5773 4350);
DISPLAY INVISIBLE (-5773 4350);
FORCEADD TAP..1
R 2
(-5775 4250);
FORCEPROP 3 LASTPIN (-5725 4250) SIG_NAME M_H_CPU1_SB_DQS_DP<6>
J 0
(-5715 4260);
DISPLAY 0.659574 (-5715 4260);
PAINT MONO (-5715 4260);
DISPLAY INVISIBLE (-5715 4260);
FORCEPROP 1 LASTPIN (-5725 4250) BN 6
J 2
(-5713 4258);
DISPLAY 0.489362 (-5713 4258);
PAINT GREEN (-5713 4258);
FORCEPROP 2 LAST CDS_LIB mstr_standard
J 2
(-5775 4250);
DISPLAY 0.723404 (-5775 4250);
PAINT MONO (-5775 4250);
DISPLAY INVISIBLE (-5775 4250);
FORCEPROP 1 LAST BODY_TYPE PLUMBING
J 2
(-5775 4300);
DISPLAY 0.872340 (-5775 4300);
PAINT GREEN (-5775 4300);
DISPLAY INVISIBLE (-5775 4300);
FORCEPROP 1 LAST HDL_TAP TRUE
J 2
(-6100 4125);
DISPLAY 0.872340 (-6100 4125);
DISPLAY INVISIBLE (-6100 4125);
FORCEPROP 1 LAST PATH I273
J 2
(-5773 4250);
DISPLAY 0.872340 (-5773 4250);
PAINT GREEN (-5773 4250);
DISPLAY INVISIBLE (-5773 4250);
FORCEADD TAP..1
R 2
(-5775 4150);
FORCEPROP 3 LASTPIN (-5725 4150) SIG_NAME M_H_CPU1_SB_DQS_DP<7>
J 0
(-5715 4160);
DISPLAY 0.659574 (-5715 4160);
PAINT MONO (-5715 4160);
DISPLAY INVISIBLE (-5715 4160);
FORCEPROP 1 LASTPIN (-5725 4150) BN 7
J 2
(-5713 4158);
DISPLAY 0.489362 (-5713 4158);
PAINT GREEN (-5713 4158);
FORCEPROP 2 LAST CDS_LIB mstr_standard
J 2
(-5775 4150);
DISPLAY 0.723404 (-5775 4150);
PAINT MONO (-5775 4150);
DISPLAY INVISIBLE (-5775 4150);
FORCEPROP 1 LAST BODY_TYPE PLUMBING
J 2
(-5775 4200);
DISPLAY 0.872340 (-5775 4200);
PAINT GREEN (-5775 4200);
DISPLAY INVISIBLE (-5775 4200);
FORCEPROP 1 LAST HDL_TAP TRUE
J 2
(-6100 4025);
DISPLAY 0.872340 (-6100 4025);
DISPLAY INVISIBLE (-6100 4025);
FORCEPROP 1 LAST PATH I274
J 2
(-5773 4150);
DISPLAY 0.872340 (-5773 4150);
PAINT GREEN (-5773 4150);
DISPLAY INVISIBLE (-5773 4150);
FORCEADD TAP..1
R 2
(-5975 4500);
FORCEPROP 3 LASTPIN (-5925 4500) SIG_NAME M_H_CPU1_SB_DQS_DN<3>
J 0
(-5915 4510);
DISPLAY 0.659574 (-5915 4510);
PAINT MONO (-5915 4510);
DISPLAY INVISIBLE (-5915 4510);
FORCEPROP 1 LASTPIN (-5925 4500) BN 3
J 2
(-5913 4508);
DISPLAY 0.489362 (-5913 4508);
PAINT GREEN (-5913 4508);
FORCEPROP 2 LAST CDS_LIB mstr_standard
J 2
(-5975 4500);
DISPLAY 0.723404 (-5975 4500);
PAINT MONO (-5975 4500);
DISPLAY INVISIBLE (-5975 4500);
FORCEPROP 1 LAST BODY_TYPE PLUMBING
J 2
(-5975 4550);
DISPLAY 0.872340 (-5975 4550);
PAINT GREEN (-5975 4550);
DISPLAY INVISIBLE (-5975 4550);
FORCEPROP 1 LAST HDL_TAP TRUE
J 2
(-6300 4375);
DISPLAY 0.872340 (-6300 4375);
DISPLAY INVISIBLE (-6300 4375);
FORCEPROP 1 LAST PATH I275
J 2
(-5973 4500);
DISPLAY 0.872340 (-5973 4500);
PAINT GREEN (-5973 4500);
DISPLAY INVISIBLE (-5973 4500);
FORCEADD TAP..1
R 2
(-5975 4400);
FORCEPROP 3 LASTPIN (-5925 4400) SIG_NAME M_H_CPU1_SB_DQS_DN<4>
J 0
(-5915 4410);
DISPLAY 0.659574 (-5915 4410);
PAINT MONO (-5915 4410);
DISPLAY INVISIBLE (-5915 4410);
FORCEPROP 1 LASTPIN (-5925 4400) BN 4
J 2
(-5913 4408);
DISPLAY 0.489362 (-5913 4408);
PAINT GREEN (-5913 4408);
FORCEPROP 2 LAST CDS_LIB mstr_standard
J 2
(-5975 4400);
DISPLAY 0.723404 (-5975 4400);
PAINT MONO (-5975 4400);
DISPLAY INVISIBLE (-5975 4400);
FORCEPROP 1 LAST BODY_TYPE PLUMBING
J 2
(-5975 4450);
DISPLAY 0.872340 (-5975 4450);
PAINT GREEN (-5975 4450);
DISPLAY INVISIBLE (-5975 4450);
FORCEPROP 1 LAST HDL_TAP TRUE
J 2
(-6300 4275);
DISPLAY 0.872340 (-6300 4275);
DISPLAY INVISIBLE (-6300 4275);
FORCEPROP 1 LAST PATH I276
J 2
(-5973 4400);
DISPLAY 0.872340 (-5973 4400);
PAINT GREEN (-5973 4400);
DISPLAY INVISIBLE (-5973 4400);
FORCEADD TAP..1
R 2
(-5975 4300);
FORCEPROP 3 LASTPIN (-5925 4300) SIG_NAME M_H_CPU1_SB_DQS_DN<5>
J 0
(-5915 4310);
DISPLAY 0.659574 (-5915 4310);
PAINT MONO (-5915 4310);
DISPLAY INVISIBLE (-5915 4310);
FORCEPROP 1 LASTPIN (-5925 4300) BN 5
J 2
(-5913 4308);
DISPLAY 0.489362 (-5913 4308);
PAINT GREEN (-5913 4308);
FORCEPROP 2 LAST CDS_LIB mstr_standard
J 2
(-5975 4300);
DISPLAY 0.723404 (-5975 4300);
PAINT MONO (-5975 4300);
DISPLAY INVISIBLE (-5975 4300);
FORCEPROP 1 LAST BODY_TYPE PLUMBING
J 2
(-5975 4350);
DISPLAY 0.872340 (-5975 4350);
PAINT GREEN (-5975 4350);
DISPLAY INVISIBLE (-5975 4350);
FORCEPROP 1 LAST HDL_TAP TRUE
J 2
(-6300 4175);
DISPLAY 0.872340 (-6300 4175);
DISPLAY INVISIBLE (-6300 4175);
FORCEPROP 1 LAST PATH I277
J 2
(-5973 4300);
DISPLAY 0.872340 (-5973 4300);
PAINT GREEN (-5973 4300);
DISPLAY INVISIBLE (-5973 4300);
FORCEADD TAP..1
R 2
(-5975 4200);
FORCEPROP 3 LASTPIN (-5925 4200) SIG_NAME M_H_CPU1_SB_DQS_DN<6>
J 0
(-5915 4210);
DISPLAY 0.659574 (-5915 4210);
PAINT MONO (-5915 4210);
DISPLAY INVISIBLE (-5915 4210);
FORCEPROP 1 LASTPIN (-5925 4200) BN 6
J 2
(-5913 4208);
DISPLAY 0.489362 (-5913 4208);
PAINT GREEN (-5913 4208);
FORCEPROP 2 LAST CDS_LIB mstr_standard
J 2
(-5975 4200);
DISPLAY 0.723404 (-5975 4200);
PAINT MONO (-5975 4200);
DISPLAY INVISIBLE (-5975 4200);
FORCEPROP 1 LAST BODY_TYPE PLUMBING
J 2
(-5975 4250);
DISPLAY 0.872340 (-5975 4250);
PAINT GREEN (-5975 4250);
DISPLAY INVISIBLE (-5975 4250);
FORCEPROP 1 LAST HDL_TAP TRUE
J 2
(-6300 4075);
DISPLAY 0.872340 (-6300 4075);
DISPLAY INVISIBLE (-6300 4075);
FORCEPROP 1 LAST PATH I278
J 2
(-5973 4200);
DISPLAY 0.872340 (-5973 4200);
PAINT GREEN (-5973 4200);
DISPLAY INVISIBLE (-5973 4200);
FORCEADD TAP..1
R 2
(-5975 4100);
FORCEPROP 3 LASTPIN (-5925 4100) SIG_NAME M_H_CPU1_SB_DQS_DN<7>
J 0
(-5915 4110);
DISPLAY 0.659574 (-5915 4110);
PAINT MONO (-5915 4110);
DISPLAY INVISIBLE (-5915 4110);
FORCEPROP 1 LASTPIN (-5925 4100) BN 7
J 2
(-5913 4108);
DISPLAY 0.489362 (-5913 4108);
PAINT GREEN (-5913 4108);
FORCEPROP 2 LAST CDS_LIB mstr_standard
J 2
(-5975 4100);
DISPLAY 0.723404 (-5975 4100);
PAINT MONO (-5975 4100);
DISPLAY INVISIBLE (-5975 4100);
FORCEPROP 1 LAST BODY_TYPE PLUMBING
J 2
(-5975 4150);
DISPLAY 0.872340 (-5975 4150);
PAINT GREEN (-5975 4150);
DISPLAY INVISIBLE (-5975 4150);
FORCEPROP 1 LAST HDL_TAP TRUE
J 2
(-6300 3975);
DISPLAY 0.872340 (-6300 3975);
DISPLAY INVISIBLE (-6300 3975);
FORCEPROP 1 LAST PATH I279
J 2
(-5973 4100);
DISPLAY 0.872340 (-5973 4100);
PAINT GREEN (-5973 4100);
DISPLAY INVISIBLE (-5973 4100);
FORCEADD OFFPAGE..3
R 2
(-6675 5925);
FORCEPROP 2 LAST $XR0 104 
J 0
(-6955 5925);
DISPLAY 0.638298 (-6955 5925);
PAINT MONO (-6955 5925);
FORCEPROP 2 LAST PATH I280
J 0
(-6975 5975);
DISPLAY 1.021277 (-6975 5975);
DISPLAY INVISIBLE (-6975 5975);
FORCEPROP 1 LAST COMMENT_BODY TRUE
J 2
(-6625 5825);
DISPLAY 0.872340 (-6625 5825);
PAINT GREEN (-6625 5825);
DISPLAY INVISIBLE (-6625 5825);
FORCEPROP 1 LAST OFFPAGE TRUE
J 2
(-7000 5800);
DISPLAY 0.872340 (-7000 5800);
PAINT GREEN (-7000 5800);
DISPLAY INVISIBLE (-7000 5800);
FORCEPROP 2 LAST CDS_LIB standard
J 0
(-6675 5925);
DISPLAY INVISIBLE (-6675 5925);
FORCEADD OFFPAGE..3
R 2
(-6675 5875);
FORCEPROP 2 LAST $XR0 104 
J 0
(-6955 5875);
DISPLAY 0.638298 (-6955 5875);
PAINT MONO (-6955 5875);
FORCEPROP 2 LAST PATH I281
J 0
(-6975 5925);
DISPLAY 1.021277 (-6975 5925);
DISPLAY INVISIBLE (-6975 5925);
FORCEPROP 1 LAST COMMENT_BODY TRUE
J 2
(-6625 5775);
DISPLAY 0.872340 (-6625 5775);
PAINT GREEN (-6625 5775);
DISPLAY INVISIBLE (-6625 5775);
FORCEPROP 1 LAST OFFPAGE TRUE
J 2
(-7000 5750);
DISPLAY 0.872340 (-7000 5750);
PAINT GREEN (-7000 5750);
DISPLAY INVISIBLE (-7000 5750);
FORCEPROP 2 LAST CDS_LIB standard
J 0
(-6675 5875);
DISPLAY INVISIBLE (-6675 5875);
FORCEADD OFFPAGE..3
R 2
(-6675 4875);
FORCEPROP 2 LAST $XR0 104 
J 0
(-6955 4875);
DISPLAY 0.638298 (-6955 4875);
PAINT MONO (-6955 4875);
FORCEPROP 2 LAST PATH I282
J 0
(-6975 4925);
DISPLAY 1.021277 (-6975 4925);
DISPLAY INVISIBLE (-6975 4925);
FORCEPROP 1 LAST COMMENT_BODY TRUE
J 2
(-6625 4775);
DISPLAY 0.872340 (-6625 4775);
PAINT GREEN (-6625 4775);
DISPLAY INVISIBLE (-6625 4775);
FORCEPROP 1 LAST OFFPAGE TRUE
J 2
(-7000 4750);
DISPLAY 0.872340 (-7000 4750);
PAINT GREEN (-7000 4750);
DISPLAY INVISIBLE (-7000 4750);
FORCEPROP 2 LAST CDS_LIB standard
J 0
(-6675 4875);
DISPLAY INVISIBLE (-6675 4875);
FORCEADD OFFPAGE..3
R 2
(-6675 4825);
FORCEPROP 2 LAST $XR0 104 
J 0
(-6955 4825);
DISPLAY 0.638298 (-6955 4825);
PAINT MONO (-6955 4825);
FORCEPROP 2 LAST PATH I283
J 0
(-6975 4875);
DISPLAY 1.021277 (-6975 4875);
DISPLAY INVISIBLE (-6975 4875);
FORCEPROP 1 LAST COMMENT_BODY TRUE
J 2
(-6625 4725);
DISPLAY 0.872340 (-6625 4725);
PAINT GREEN (-6625 4725);
DISPLAY INVISIBLE (-6625 4725);
FORCEPROP 1 LAST OFFPAGE TRUE
J 2
(-7000 4700);
DISPLAY 0.872340 (-7000 4700);
PAINT GREEN (-7000 4700);
DISPLAY INVISIBLE (-7000 4700);
FORCEPROP 2 LAST CDS_LIB standard
J 0
(-6675 4825);
DISPLAY INVISIBLE (-6675 4825);
FORCEADD TAP..1
R 2
(-5775 4050);
FORCEPROP 3 LASTPIN (-5725 4050) SIG_NAME M_H_CPU1_SB_DQS_DP<8>
J 0
(-5715 4060);
DISPLAY 0.659574 (-5715 4060);
PAINT MONO (-5715 4060);
DISPLAY INVISIBLE (-5715 4060);
FORCEPROP 1 LASTPIN (-5725 4050) BN 8
J 2
(-5713 4058);
DISPLAY 0.489362 (-5713 4058);
PAINT GREEN (-5713 4058);
FORCEPROP 2 LAST CDS_LIB mstr_standard
J 2
(-5775 4050);
DISPLAY 0.723404 (-5775 4050);
PAINT MONO (-5775 4050);
DISPLAY INVISIBLE (-5775 4050);
FORCEPROP 1 LAST BODY_TYPE PLUMBING
J 2
(-5775 4100);
DISPLAY 0.872340 (-5775 4100);
PAINT GREEN (-5775 4100);
DISPLAY INVISIBLE (-5775 4100);
FORCEPROP 1 LAST HDL_TAP TRUE
J 2
(-6100 3925);
DISPLAY 0.872340 (-6100 3925);
DISPLAY INVISIBLE (-6100 3925);
FORCEPROP 1 LAST PATH I284
J 2
(-5773 4050);
DISPLAY 0.872340 (-5773 4050);
PAINT GREEN (-5773 4050);
DISPLAY INVISIBLE (-5773 4050);
FORCEADD TAP..1
R 2
(-5775 3950);
FORCEPROP 3 LASTPIN (-5725 3950) SIG_NAME M_H_CPU1_SB_DQS_DP<9>
J 0
(-5715 3960);
DISPLAY 0.659574 (-5715 3960);
PAINT MONO (-5715 3960);
DISPLAY INVISIBLE (-5715 3960);
FORCEPROP 1 LASTPIN (-5725 3950) BN 9
J 2
(-5713 3958);
DISPLAY 0.489362 (-5713 3958);
PAINT GREEN (-5713 3958);
FORCEPROP 2 LAST CDS_LIB mstr_standard
J 2
(-5775 3950);
DISPLAY 0.723404 (-5775 3950);
PAINT MONO (-5775 3950);
DISPLAY INVISIBLE (-5775 3950);
FORCEPROP 1 LAST BODY_TYPE PLUMBING
J 2
(-5775 4000);
DISPLAY 0.872340 (-5775 4000);
PAINT GREEN (-5775 4000);
DISPLAY INVISIBLE (-5775 4000);
FORCEPROP 1 LAST HDL_TAP TRUE
J 2
(-6100 3825);
DISPLAY 0.872340 (-6100 3825);
DISPLAY INVISIBLE (-6100 3825);
FORCEPROP 1 LAST PATH I285
J 2
(-5773 3950);
DISPLAY 0.872340 (-5773 3950);
PAINT GREEN (-5773 3950);
DISPLAY INVISIBLE (-5773 3950);
FORCEADD TAP..1
R 2
(-5975 4000);
FORCEPROP 3 LASTPIN (-5925 4000) SIG_NAME M_H_CPU1_SB_DQS_DN<8>
J 0
(-5915 4010);
DISPLAY 0.659574 (-5915 4010);
PAINT MONO (-5915 4010);
DISPLAY INVISIBLE (-5915 4010);
FORCEPROP 1 LASTPIN (-5925 4000) BN 8
J 2
(-5913 4008);
DISPLAY 0.489362 (-5913 4008);
PAINT GREEN (-5913 4008);
FORCEPROP 2 LAST CDS_LIB mstr_standard
J 2
(-5975 4000);
DISPLAY 0.723404 (-5975 4000);
PAINT MONO (-5975 4000);
DISPLAY INVISIBLE (-5975 4000);
FORCEPROP 1 LAST BODY_TYPE PLUMBING
J 2
(-5975 4050);
DISPLAY 0.872340 (-5975 4050);
PAINT GREEN (-5975 4050);
DISPLAY INVISIBLE (-5975 4050);
FORCEPROP 1 LAST HDL_TAP TRUE
J 2
(-6300 3875);
DISPLAY 0.872340 (-6300 3875);
DISPLAY INVISIBLE (-6300 3875);
FORCEPROP 1 LAST PATH I286
J 2
(-5973 4000);
DISPLAY 0.872340 (-5973 4000);
PAINT GREEN (-5973 4000);
DISPLAY INVISIBLE (-5973 4000);
FORCEADD TAP..1
R 2
(-5975 3900);
FORCEPROP 3 LASTPIN (-5925 3900) SIG_NAME M_H_CPU1_SB_DQS_DN<9>
J 0
(-5915 3910);
DISPLAY 0.659574 (-5915 3910);
PAINT MONO (-5915 3910);
DISPLAY INVISIBLE (-5915 3910);
FORCEPROP 1 LASTPIN (-5925 3900) BN 9
J 2
(-5913 3908);
DISPLAY 0.489362 (-5913 3908);
PAINT GREEN (-5913 3908);
FORCEPROP 2 LAST CDS_LIB mstr_standard
J 2
(-5975 3900);
DISPLAY 0.723404 (-5975 3900);
PAINT MONO (-5975 3900);
DISPLAY INVISIBLE (-5975 3900);
FORCEPROP 1 LAST BODY_TYPE PLUMBING
J 2
(-5975 3950);
DISPLAY 0.872340 (-5975 3950);
PAINT GREEN (-5975 3950);
DISPLAY INVISIBLE (-5975 3950);
FORCEPROP 1 LAST HDL_TAP TRUE
J 2
(-6300 3775);
DISPLAY 0.872340 (-6300 3775);
DISPLAY INVISIBLE (-6300 3775);
FORCEPROP 1 LAST PATH I287
J 2
(-5973 3900);
DISPLAY 0.872340 (-5973 3900);
PAINT GREEN (-5973 3900);
DISPLAY INVISIBLE (-5973 3900);
FORCEADD TAP..1
R 2
(-5975 3750);
FORCEPROP 3 LASTPIN (-5925 3750) SIG_NAME M_H_CPU1_SA_CA<0>
J 0
(-5915 3760);
DISPLAY 0.659574 (-5915 3760);
PAINT MONO (-5915 3760);
DISPLAY INVISIBLE (-5915 3760);
FORCEPROP 1 LASTPIN (-5925 3750) BN 0
J 2
(-5913 3758);
DISPLAY 0.489362 (-5913 3758);
PAINT GREEN (-5913 3758);
FORCEPROP 2 LAST CDS_LIB mstr_standard
J 0
(-5975 3750);
DISPLAY 0.723404 (-5975 3750);
PAINT MONO (-5975 3750);
DISPLAY INVISIBLE (-5975 3750);
FORCEPROP 1 LAST BODY_TYPE PLUMBING
J 2
(-5975 3800);
DISPLAY 0.872340 (-5975 3800);
PAINT GREEN (-5975 3800);
DISPLAY INVISIBLE (-5975 3800);
FORCEPROP 1 LAST HDL_TAP TRUE
J 2
(-6300 3625);
DISPLAY 0.872340 (-6300 3625);
DISPLAY INVISIBLE (-6300 3625);
FORCEPROP 1 LAST PATH I288
J 2
(-5973 3750);
DISPLAY 0.872340 (-5973 3750);
PAINT GREEN (-5973 3750);
DISPLAY INVISIBLE (-5973 3750);
FORCEADD TAP..1
R 2
(-5975 3700);
FORCEPROP 3 LASTPIN (-5925 3700) SIG_NAME M_H_CPU1_SA_CA<1>
J 0
(-5915 3710);
DISPLAY 0.659574 (-5915 3710);
PAINT MONO (-5915 3710);
DISPLAY INVISIBLE (-5915 3710);
FORCEPROP 1 LASTPIN (-5925 3700) BN 1
J 2
(-5913 3708);
DISPLAY 0.489362 (-5913 3708);
PAINT GREEN (-5913 3708);
FORCEPROP 2 LAST CDS_LIB mstr_standard
J 0
(-5975 3700);
DISPLAY 0.723404 (-5975 3700);
PAINT MONO (-5975 3700);
DISPLAY INVISIBLE (-5975 3700);
FORCEPROP 1 LAST BODY_TYPE PLUMBING
J 2
(-5975 3750);
DISPLAY 0.872340 (-5975 3750);
PAINT GREEN (-5975 3750);
DISPLAY INVISIBLE (-5975 3750);
FORCEPROP 1 LAST HDL_TAP TRUE
J 2
(-6300 3575);
DISPLAY 0.872340 (-6300 3575);
DISPLAY INVISIBLE (-6300 3575);
FORCEPROP 1 LAST PATH I289
J 2
(-5973 3700);
DISPLAY 0.872340 (-5973 3700);
PAINT GREEN (-5973 3700);
DISPLAY INVISIBLE (-5973 3700);
FORCEADD TAP..1
R 2
(-5975 3650);
FORCEPROP 3 LASTPIN (-5925 3650) SIG_NAME M_H_CPU1_SA_CA<2>
J 0
(-5915 3660);
DISPLAY 0.659574 (-5915 3660);
PAINT MONO (-5915 3660);
DISPLAY INVISIBLE (-5915 3660);
FORCEPROP 1 LASTPIN (-5925 3650) BN 2
J 2
(-5913 3658);
DISPLAY 0.489362 (-5913 3658);
PAINT GREEN (-5913 3658);
FORCEPROP 2 LAST CDS_LIB mstr_standard
J 0
(-5975 3650);
DISPLAY 0.723404 (-5975 3650);
PAINT MONO (-5975 3650);
DISPLAY INVISIBLE (-5975 3650);
FORCEPROP 1 LAST BODY_TYPE PLUMBING
J 2
(-5975 3700);
DISPLAY 0.872340 (-5975 3700);
PAINT GREEN (-5975 3700);
DISPLAY INVISIBLE (-5975 3700);
FORCEPROP 1 LAST HDL_TAP TRUE
J 2
(-6300 3525);
DISPLAY 0.872340 (-6300 3525);
DISPLAY INVISIBLE (-6300 3525);
FORCEPROP 1 LAST PATH I290
J 2
(-5973 3650);
DISPLAY 0.872340 (-5973 3650);
PAINT GREEN (-5973 3650);
DISPLAY INVISIBLE (-5973 3650);
FORCEADD TAP..1
R 2
(-5975 3600);
FORCEPROP 3 LASTPIN (-5925 3600) SIG_NAME M_H_CPU1_SA_CA<3>
J 0
(-5915 3610);
DISPLAY 0.659574 (-5915 3610);
PAINT MONO (-5915 3610);
DISPLAY INVISIBLE (-5915 3610);
FORCEPROP 1 LASTPIN (-5925 3600) BN 3
J 2
(-5913 3608);
DISPLAY 0.489362 (-5913 3608);
PAINT GREEN (-5913 3608);
FORCEPROP 2 LAST CDS_LIB mstr_standard
J 0
(-5975 3600);
DISPLAY 0.723404 (-5975 3600);
PAINT MONO (-5975 3600);
DISPLAY INVISIBLE (-5975 3600);
FORCEPROP 1 LAST BODY_TYPE PLUMBING
J 2
(-5975 3650);
DISPLAY 0.872340 (-5975 3650);
PAINT GREEN (-5975 3650);
DISPLAY INVISIBLE (-5975 3650);
FORCEPROP 1 LAST HDL_TAP TRUE
J 2
(-6300 3475);
DISPLAY 0.872340 (-6300 3475);
DISPLAY INVISIBLE (-6300 3475);
FORCEPROP 1 LAST PATH I291
J 2
(-5973 3600);
DISPLAY 0.872340 (-5973 3600);
PAINT GREEN (-5973 3600);
DISPLAY INVISIBLE (-5973 3600);
FORCEADD TAP..1
R 2
(-5975 3500);
FORCEPROP 3 LASTPIN (-5925 3500) SIG_NAME M_H_CPU1_SA_CA<5>
J 0
(-5915 3510);
DISPLAY 0.659574 (-5915 3510);
PAINT MONO (-5915 3510);
DISPLAY INVISIBLE (-5915 3510);
FORCEPROP 1 LASTPIN (-5925 3500) BN 5
J 2
(-5913 3508);
DISPLAY 0.489362 (-5913 3508);
PAINT GREEN (-5913 3508);
FORCEPROP 2 LAST CDS_LIB mstr_standard
J 0
(-5975 3500);
DISPLAY 0.723404 (-5975 3500);
PAINT MONO (-5975 3500);
DISPLAY INVISIBLE (-5975 3500);
FORCEPROP 1 LAST BODY_TYPE PLUMBING
J 2
(-5975 3550);
DISPLAY 0.872340 (-5975 3550);
PAINT GREEN (-5975 3550);
DISPLAY INVISIBLE (-5975 3550);
FORCEPROP 1 LAST HDL_TAP TRUE
J 2
(-6300 3375);
DISPLAY 0.872340 (-6300 3375);
DISPLAY INVISIBLE (-6300 3375);
FORCEPROP 1 LAST PATH I292
J 2
(-5973 3500);
DISPLAY 0.872340 (-5973 3500);
PAINT GREEN (-5973 3500);
DISPLAY INVISIBLE (-5973 3500);
FORCEADD TAP..1
R 2
(-5975 3550);
FORCEPROP 3 LASTPIN (-5925 3550) SIG_NAME M_H_CPU1_SA_CA<4>
J 0
(-5915 3560);
DISPLAY 0.659574 (-5915 3560);
PAINT MONO (-5915 3560);
DISPLAY INVISIBLE (-5915 3560);
FORCEPROP 1 LASTPIN (-5925 3550) BN 4
J 2
(-5913 3558);
DISPLAY 0.489362 (-5913 3558);
PAINT GREEN (-5913 3558);
FORCEPROP 2 LAST CDS_LIB mstr_standard
J 0
(-5975 3550);
DISPLAY 0.723404 (-5975 3550);
PAINT MONO (-5975 3550);
DISPLAY INVISIBLE (-5975 3550);
FORCEPROP 1 LAST BODY_TYPE PLUMBING
J 2
(-5975 3600);
DISPLAY 0.872340 (-5975 3600);
PAINT GREEN (-5975 3600);
DISPLAY INVISIBLE (-5975 3600);
FORCEPROP 1 LAST HDL_TAP TRUE
J 2
(-6300 3425);
DISPLAY 0.872340 (-6300 3425);
DISPLAY INVISIBLE (-6300 3425);
FORCEPROP 1 LAST PATH I293
J 2
(-5973 3550);
DISPLAY 0.872340 (-5973 3550);
PAINT GREEN (-5973 3550);
DISPLAY INVISIBLE (-5973 3550);
FORCEADD TAP..1
R 2
(-5975 3450);
FORCEPROP 3 LASTPIN (-5925 3450) SIG_NAME M_H_CPU1_SA_CA<6>
J 0
(-5915 3460);
DISPLAY 0.659574 (-5915 3460);
PAINT MONO (-5915 3460);
DISPLAY INVISIBLE (-5915 3460);
FORCEPROP 1 LASTPIN (-5925 3450) BN 6
J 2
(-5913 3458);
DISPLAY 0.489362 (-5913 3458);
PAINT GREEN (-5913 3458);
FORCEPROP 2 LAST CDS_LIB mstr_standard
J 0
(-5975 3450);
DISPLAY 0.723404 (-5975 3450);
PAINT MONO (-5975 3450);
DISPLAY INVISIBLE (-5975 3450);
FORCEPROP 1 LAST BODY_TYPE PLUMBING
J 2
(-5975 3500);
DISPLAY 0.872340 (-5975 3500);
PAINT GREEN (-5975 3500);
DISPLAY INVISIBLE (-5975 3500);
FORCEPROP 1 LAST HDL_TAP TRUE
J 2
(-6300 3325);
DISPLAY 0.872340 (-6300 3325);
DISPLAY INVISIBLE (-6300 3325);
FORCEPROP 1 LAST PATH I294
J 2
(-5973 3450);
DISPLAY 0.872340 (-5973 3450);
PAINT GREEN (-5973 3450);
DISPLAY INVISIBLE (-5973 3450);
FORCEADD TAP..1
R 2
(-5975 3350);
FORCEPROP 3 LASTPIN (-5925 3350) SIG_NAME M_H_CPU1_SB_CA<0>
J 0
(-5915 3360);
DISPLAY 0.659574 (-5915 3360);
PAINT MONO (-5915 3360);
DISPLAY INVISIBLE (-5915 3360);
FORCEPROP 1 LASTPIN (-5925 3350) BN 0
J 2
(-5913 3358);
DISPLAY 0.489362 (-5913 3358);
PAINT GREEN (-5913 3358);
FORCEPROP 2 LAST CDS_LIB mstr_standard
J 0
(-5975 3350);
DISPLAY 0.723404 (-5975 3350);
PAINT MONO (-5975 3350);
DISPLAY INVISIBLE (-5975 3350);
FORCEPROP 1 LAST BODY_TYPE PLUMBING
J 2
(-5975 3400);
DISPLAY 0.872340 (-5975 3400);
PAINT GREEN (-5975 3400);
DISPLAY INVISIBLE (-5975 3400);
FORCEPROP 1 LAST HDL_TAP TRUE
J 2
(-6300 3225);
DISPLAY 0.872340 (-6300 3225);
DISPLAY INVISIBLE (-6300 3225);
FORCEPROP 1 LAST PATH I295
J 2
(-5973 3350);
DISPLAY 0.872340 (-5973 3350);
PAINT GREEN (-5973 3350);
DISPLAY INVISIBLE (-5973 3350);
FORCEADD TAP..1
R 2
(-5975 3250);
FORCEPROP 3 LASTPIN (-5925 3250) SIG_NAME M_H_CPU1_SB_CA<2>
J 0
(-5915 3260);
DISPLAY 0.659574 (-5915 3260);
PAINT MONO (-5915 3260);
DISPLAY INVISIBLE (-5915 3260);
FORCEPROP 1 LASTPIN (-5925 3250) BN 2
J 2
(-5913 3258);
DISPLAY 0.489362 (-5913 3258);
PAINT GREEN (-5913 3258);
FORCEPROP 2 LAST CDS_LIB mstr_standard
J 0
(-5975 3250);
DISPLAY 0.723404 (-5975 3250);
PAINT MONO (-5975 3250);
DISPLAY INVISIBLE (-5975 3250);
FORCEPROP 1 LAST BODY_TYPE PLUMBING
J 2
(-5975 3300);
DISPLAY 0.872340 (-5975 3300);
PAINT GREEN (-5975 3300);
DISPLAY INVISIBLE (-5975 3300);
FORCEPROP 1 LAST HDL_TAP TRUE
J 2
(-6300 3125);
DISPLAY 0.872340 (-6300 3125);
DISPLAY INVISIBLE (-6300 3125);
FORCEPROP 1 LAST PATH I296
J 2
(-5973 3250);
DISPLAY 0.872340 (-5973 3250);
PAINT GREEN (-5973 3250);
DISPLAY INVISIBLE (-5973 3250);
FORCEADD TAP..1
R 2
(-5975 3300);
FORCEPROP 3 LASTPIN (-5925 3300) SIG_NAME M_H_CPU1_SB_CA<1>
J 0
(-5915 3310);
DISPLAY 0.659574 (-5915 3310);
PAINT MONO (-5915 3310);
DISPLAY INVISIBLE (-5915 3310);
FORCEPROP 1 LASTPIN (-5925 3300) BN 1
J 2
(-5913 3308);
DISPLAY 0.489362 (-5913 3308);
PAINT GREEN (-5913 3308);
FORCEPROP 2 LAST CDS_LIB mstr_standard
J 0
(-5975 3300);
DISPLAY 0.723404 (-5975 3300);
PAINT MONO (-5975 3300);
DISPLAY INVISIBLE (-5975 3300);
FORCEPROP 1 LAST BODY_TYPE PLUMBING
J 2
(-5975 3350);
DISPLAY 0.872340 (-5975 3350);
PAINT GREEN (-5975 3350);
DISPLAY INVISIBLE (-5975 3350);
FORCEPROP 1 LAST HDL_TAP TRUE
J 2
(-6300 3175);
DISPLAY 0.872340 (-6300 3175);
DISPLAY INVISIBLE (-6300 3175);
FORCEPROP 1 LAST PATH I297
J 2
(-5973 3300);
DISPLAY 0.872340 (-5973 3300);
PAINT GREEN (-5973 3300);
DISPLAY INVISIBLE (-5973 3300);
FORCEADD TAP..1
R 2
(-5975 3200);
FORCEPROP 3 LASTPIN (-5925 3200) SIG_NAME M_H_CPU1_SB_CA<3>
J 0
(-5915 3210);
DISPLAY 0.659574 (-5915 3210);
PAINT MONO (-5915 3210);
DISPLAY INVISIBLE (-5915 3210);
FORCEPROP 1 LASTPIN (-5925 3200) BN 3
J 2
(-5913 3208);
DISPLAY 0.489362 (-5913 3208);
PAINT GREEN (-5913 3208);
FORCEPROP 2 LAST CDS_LIB mstr_standard
J 0
(-5975 3200);
DISPLAY 0.723404 (-5975 3200);
PAINT MONO (-5975 3200);
DISPLAY INVISIBLE (-5975 3200);
FORCEPROP 1 LAST BODY_TYPE PLUMBING
J 2
(-5975 3250);
DISPLAY 0.872340 (-5975 3250);
PAINT GREEN (-5975 3250);
DISPLAY INVISIBLE (-5975 3250);
FORCEPROP 1 LAST HDL_TAP TRUE
J 2
(-6300 3075);
DISPLAY 0.872340 (-6300 3075);
DISPLAY INVISIBLE (-6300 3075);
FORCEPROP 1 LAST PATH I298
J 2
(-5973 3200);
DISPLAY 0.872340 (-5973 3200);
PAINT GREEN (-5973 3200);
DISPLAY INVISIBLE (-5973 3200);
FORCEADD TAP..1
R 2
(-5975 3100);
FORCEPROP 3 LASTPIN (-5925 3100) SIG_NAME M_H_CPU1_SB_CA<5>
J 0
(-5915 3110);
DISPLAY 0.659574 (-5915 3110);
PAINT MONO (-5915 3110);
DISPLAY INVISIBLE (-5915 3110);
FORCEPROP 1 LASTPIN (-5925 3100) BN 5
J 2
(-5913 3108);
DISPLAY 0.489362 (-5913 3108);
PAINT GREEN (-5913 3108);
FORCEPROP 2 LAST CDS_LIB mstr_standard
J 0
(-5975 3100);
DISPLAY 0.723404 (-5975 3100);
PAINT MONO (-5975 3100);
DISPLAY INVISIBLE (-5975 3100);
FORCEPROP 1 LAST BODY_TYPE PLUMBING
J 2
(-5975 3150);
DISPLAY 0.872340 (-5975 3150);
PAINT GREEN (-5975 3150);
DISPLAY INVISIBLE (-5975 3150);
FORCEPROP 1 LAST HDL_TAP TRUE
J 2
(-6300 2975);
DISPLAY 0.872340 (-6300 2975);
DISPLAY INVISIBLE (-6300 2975);
FORCEPROP 1 LAST PATH I299
J 2
(-5973 3100);
DISPLAY 0.872340 (-5973 3100);
PAINT GREEN (-5973 3100);
DISPLAY INVISIBLE (-5973 3100);
FORCEADD TAP..1
R 2
(-5975 3150);
FORCEPROP 3 LASTPIN (-5925 3150) SIG_NAME M_H_CPU1_SB_CA<4>
J 0
(-5915 3160);
DISPLAY 0.659574 (-5915 3160);
PAINT MONO (-5915 3160);
DISPLAY INVISIBLE (-5915 3160);
FORCEPROP 1 LASTPIN (-5925 3150) BN 4
J 2
(-5913 3158);
DISPLAY 0.489362 (-5913 3158);
PAINT GREEN (-5913 3158);
FORCEPROP 2 LAST CDS_LIB mstr_standard
J 0
(-5975 3150);
DISPLAY 0.723404 (-5975 3150);
PAINT MONO (-5975 3150);
DISPLAY INVISIBLE (-5975 3150);
FORCEPROP 1 LAST BODY_TYPE PLUMBING
J 2
(-5975 3200);
DISPLAY 0.872340 (-5975 3200);
PAINT GREEN (-5975 3200);
DISPLAY INVISIBLE (-5975 3200);
FORCEPROP 1 LAST HDL_TAP TRUE
J 2
(-6300 3025);
DISPLAY 0.872340 (-6300 3025);
DISPLAY INVISIBLE (-6300 3025);
FORCEPROP 1 LAST PATH I300
J 2
(-5973 3150);
DISPLAY 0.872340 (-5973 3150);
PAINT GREEN (-5973 3150);
DISPLAY INVISIBLE (-5973 3150);
FORCEADD TAP..1
R 2
(-5975 3050);
FORCEPROP 3 LASTPIN (-5925 3050) SIG_NAME M_H_CPU1_SB_CA<6>
J 0
(-5915 3060);
DISPLAY 0.659574 (-5915 3060);
PAINT MONO (-5915 3060);
DISPLAY INVISIBLE (-5915 3060);
FORCEPROP 1 LASTPIN (-5925 3050) BN 6
J 2
(-5913 3058);
DISPLAY 0.489362 (-5913 3058);
PAINT GREEN (-5913 3058);
FORCEPROP 2 LAST CDS_LIB mstr_standard
J 0
(-5975 3050);
DISPLAY 0.723404 (-5975 3050);
PAINT MONO (-5975 3050);
DISPLAY INVISIBLE (-5975 3050);
FORCEPROP 1 LAST BODY_TYPE PLUMBING
J 2
(-5975 3100);
DISPLAY 0.872340 (-5975 3100);
PAINT GREEN (-5975 3100);
DISPLAY INVISIBLE (-5975 3100);
FORCEPROP 1 LAST HDL_TAP TRUE
J 2
(-6300 2925);
DISPLAY 0.872340 (-6300 2925);
DISPLAY INVISIBLE (-6300 2925);
FORCEPROP 1 LAST PATH I301
J 2
(-5973 3050);
DISPLAY 0.872340 (-5973 3050);
PAINT GREEN (-5973 3050);
DISPLAY INVISIBLE (-5973 3050);
FORCEADD OFFPAGE..2
R 2
(-6575 3775);
FORCEPROP 2 LAST $XR0 104 
J 0
(-6830 3775);
DISPLAY 0.638298 (-6830 3775);
PAINT MONO (-6830 3775);
FORCEPROP 2 LAST PATH I302
J 0
(-6825 3825);
DISPLAY 1.021277 (-6825 3825);
DISPLAY INVISIBLE (-6825 3825);
FORCEPROP 1 LAST COMMENT_BODY TRUE
J 2
(-6530 3680);
DISPLAY 0.872340 (-6530 3680);
PAINT GREEN (-6530 3680);
DISPLAY INVISIBLE (-6530 3680);
FORCEPROP 1 LAST OFFPAGE TRUE
J 2
(-6900 3650);
DISPLAY 0.872340 (-6900 3650);
PAINT GREEN (-6900 3650);
DISPLAY INVISIBLE (-6900 3650);
FORCEPROP 2 LAST CDS_LIB standard
J 0
(-6575 3775);
DISPLAY INVISIBLE (-6575 3775);
FORCEADD OFFPAGE..2
R 2
(-6575 3375);
FORCEPROP 2 LAST $XR0 104 
J 0
(-6830 3375);
DISPLAY 0.638298 (-6830 3375);
PAINT MONO (-6830 3375);
FORCEPROP 2 LAST PATH I303
J 0
(-6825 3425);
DISPLAY 1.021277 (-6825 3425);
DISPLAY INVISIBLE (-6825 3425);
FORCEPROP 1 LAST COMMENT_BODY TRUE
J 2
(-6530 3280);
DISPLAY 0.872340 (-6530 3280);
PAINT GREEN (-6530 3280);
DISPLAY INVISIBLE (-6530 3280);
FORCEPROP 1 LAST OFFPAGE TRUE
J 2
(-6900 3250);
DISPLAY 0.872340 (-6900 3250);
PAINT GREEN (-6900 3250);
DISPLAY INVISIBLE (-6900 3250);
FORCEPROP 2 LAST CDS_LIB standard
J 0
(-6575 3375);
DISPLAY INVISIBLE (-6575 3375);
FORCEADD OFFPAGE..2
R 2
(-6575 2850);
FORCEPROP 2 LAST $XR0 104 
J 0
(-6830 2850);
DISPLAY 0.638298 (-6830 2850);
PAINT MONO (-6830 2850);
FORCEPROP 2 LAST PATH I304
J 0
(-6825 2900);
DISPLAY 1.021277 (-6825 2900);
DISPLAY INVISIBLE (-6825 2900);
FORCEPROP 1 LAST COMMENT_BODY TRUE
J 2
(-6530 2755);
DISPLAY 0.872340 (-6530 2755);
PAINT GREEN (-6530 2755);
DISPLAY INVISIBLE (-6530 2755);
FORCEPROP 1 LAST OFFPAGE TRUE
J 2
(-6900 2725);
DISPLAY 0.872340 (-6900 2725);
PAINT GREEN (-6900 2725);
DISPLAY INVISIBLE (-6900 2725);
FORCEPROP 2 LAST CDS_LIB standard
J 0
(-6575 2850);
DISPLAY INVISIBLE (-6575 2850);
FORCEADD OFFPAGE..2
R 2
(-6575 2900);
FORCEPROP 2 LAST $XR0 104 
J 0
(-6830 2900);
DISPLAY 0.638298 (-6830 2900);
PAINT MONO (-6830 2900);
FORCEPROP 2 LAST PATH I305
J 0
(-6825 2950);
DISPLAY 1.021277 (-6825 2950);
DISPLAY INVISIBLE (-6825 2950);
FORCEPROP 1 LAST COMMENT_BODY TRUE
J 2
(-6530 2805);
DISPLAY 0.872340 (-6530 2805);
PAINT GREEN (-6530 2805);
DISPLAY INVISIBLE (-6530 2805);
FORCEPROP 1 LAST OFFPAGE TRUE
J 2
(-6900 2775);
DISPLAY 0.872340 (-6900 2775);
PAINT GREEN (-6900 2775);
DISPLAY INVISIBLE (-6900 2775);
FORCEPROP 2 LAST CDS_LIB standard
J 0
(-6575 2900);
DISPLAY INVISIBLE (-6575 2900);
FORCEADD OFFPAGE..2
R 2
(-6575 2750);
FORCEPROP 2 LAST $XR0 104 
J 0
(-6830 2750);
DISPLAY 0.638298 (-6830 2750);
PAINT MONO (-6830 2750);
FORCEPROP 2 LAST PATH I306
J 0
(-6825 2800);
DISPLAY 1.021277 (-6825 2800);
DISPLAY INVISIBLE (-6825 2800);
FORCEPROP 1 LAST COMMENT_BODY TRUE
J 2
(-6530 2655);
DISPLAY 0.872340 (-6530 2655);
PAINT GREEN (-6530 2655);
DISPLAY INVISIBLE (-6530 2655);
FORCEPROP 1 LAST OFFPAGE TRUE
J 2
(-6900 2625);
DISPLAY 0.872340 (-6900 2625);
PAINT GREEN (-6900 2625);
DISPLAY INVISIBLE (-6900 2625);
FORCEPROP 2 LAST CDS_LIB standard
J 0
(-6575 2750);
DISPLAY INVISIBLE (-6575 2750);
FORCEADD OFFPAGE..2
R 2
(-6575 2700);
FORCEPROP 2 LAST $XR0 104 
J 0
(-6830 2700);
DISPLAY 0.638298 (-6830 2700);
PAINT MONO (-6830 2700);
FORCEPROP 2 LAST PATH I307
J 0
(-6825 2750);
DISPLAY 1.021277 (-6825 2750);
DISPLAY INVISIBLE (-6825 2750);
FORCEPROP 1 LAST COMMENT_BODY TRUE
J 2
(-6530 2605);
DISPLAY 0.872340 (-6530 2605);
PAINT GREEN (-6530 2605);
DISPLAY INVISIBLE (-6530 2605);
FORCEPROP 1 LAST OFFPAGE TRUE
J 2
(-6900 2575);
DISPLAY 0.872340 (-6900 2575);
PAINT GREEN (-6900 2575);
DISPLAY INVISIBLE (-6900 2575);
FORCEPROP 2 LAST CDS_LIB standard
J 0
(-6575 2700);
DISPLAY INVISIBLE (-6575 2700);
FORCEADD OFFPAGE..1
(-6575 2600);
FORCEPROP 2 LAST $XR0 104 
J 0
(-6857 2600);
DISPLAY 0.638298 (-6857 2600);
PAINT MONO (-6857 2600);
FORCEPROP 2 LAST PATH I308
J 0
(-6850 2650);
DISPLAY 1.021277 (-6850 2650);
DISPLAY INVISIBLE (-6850 2650);
FORCEPROP 1 LAST COMMENT_BODY TRUE
J 0
(-6450 2500);
DISPLAY 0.872340 (-6450 2500);
PAINT GREEN (-6450 2500);
DISPLAY INVISIBLE (-6450 2500);
FORCEPROP 1 LAST OFFPAGE TRUE
J 0
(-6250 2475);
DISPLAY 0.872340 (-6250 2475);
PAINT GREEN (-6250 2475);
DISPLAY INVISIBLE (-6250 2475);
FORCEPROP 2 LAST CDS_LIB standard
J 0
(-6575 2600);
DISPLAY INVISIBLE (-6575 2600);
FORCEADD OFFPAGE..5
(-6575 2500);
FORCEPROP 2 LAST $XR0 104 
J 0
(-6830 2500);
DISPLAY 0.638298 (-6830 2500);
PAINT MONO (-6830 2500);
FORCEPROP 2 LAST PATH I309
J 0
(-6825 2550);
DISPLAY 1.021277 (-6825 2550);
DISPLAY INVISIBLE (-6825 2550);
FORCEPROP 1 LAST COMMENT_BODY TRUE
J 0
(-6475 2425);
DISPLAY 0.872340 (-6475 2425);
PAINT GREEN (-6475 2425);
DISPLAY INVISIBLE (-6475 2425);
FORCEPROP 1 LAST OFFPAGE TRUE
J 0
(-6250 2375);
DISPLAY 0.872340 (-6250 2375);
PAINT GREEN (-6250 2375);
DISPLAY INVISIBLE (-6250 2375);
FORCEPROP 2 LAST CDS_LIB mstr_standard
J 0
(-6575 2500);
DISPLAY INVISIBLE (-6575 2500);
FORCEADD OFFPAGE..2
R 2
(-6575 2350);
FORCEPROP 2 LAST $XR0 104 
J 0
(-6830 2350);
DISPLAY 0.638298 (-6830 2350);
PAINT MONO (-6830 2350);
FORCEPROP 2 LAST PATH I310
J 0
(-6825 2400);
DISPLAY 1.021277 (-6825 2400);
DISPLAY INVISIBLE (-6825 2400);
FORCEPROP 1 LAST COMMENT_BODY TRUE
J 2
(-6530 2255);
DISPLAY 0.872340 (-6530 2255);
PAINT GREEN (-6530 2255);
DISPLAY INVISIBLE (-6530 2255);
FORCEPROP 1 LAST OFFPAGE TRUE
J 2
(-6900 2225);
DISPLAY 0.872340 (-6900 2225);
PAINT GREEN (-6900 2225);
DISPLAY INVISIBLE (-6900 2225);
FORCEPROP 2 LAST CDS_LIB standard
J 0
(-6575 2350);
DISPLAY INVISIBLE (-6575 2350);
FORCEADD OFFPAGE..2
R 2
(-6575 2400);
FORCEPROP 2 LAST $XR0 104 
J 0
(-6830 2400);
DISPLAY 0.638298 (-6830 2400);
PAINT MONO (-6830 2400);
FORCEPROP 2 LAST PATH I311
J 0
(-6825 2450);
DISPLAY 1.021277 (-6825 2450);
DISPLAY INVISIBLE (-6825 2450);
FORCEPROP 1 LAST COMMENT_BODY TRUE
J 2
(-6530 2305);
DISPLAY 0.872340 (-6530 2305);
PAINT GREEN (-6530 2305);
DISPLAY INVISIBLE (-6530 2305);
FORCEPROP 1 LAST OFFPAGE TRUE
J 2
(-6900 2275);
DISPLAY 0.872340 (-6900 2275);
PAINT GREEN (-6900 2275);
DISPLAY INVISIBLE (-6900 2275);
FORCEPROP 2 LAST CDS_LIB standard
J 0
(-6575 2400);
DISPLAY INVISIBLE (-6575 2400);
FORCEADD OFFPAGE..1
(-6575 2250);
FORCEPROP 2 LAST $XR0 104 
J 0
(-6857 2250);
DISPLAY 0.638298 (-6857 2250);
PAINT MONO (-6857 2250);
FORCEPROP 2 LAST PATH I312
J 0
(-6850 2300);
DISPLAY 1.021277 (-6850 2300);
DISPLAY INVISIBLE (-6850 2300);
FORCEPROP 1 LAST COMMENT_BODY TRUE
J 0
(-6450 2150);
DISPLAY 0.872340 (-6450 2150);
PAINT GREEN (-6450 2150);
DISPLAY INVISIBLE (-6450 2150);
FORCEPROP 1 LAST OFFPAGE TRUE
J 0
(-6250 2125);
DISPLAY 0.872340 (-6250 2125);
PAINT GREEN (-6250 2125);
DISPLAY INVISIBLE (-6250 2125);
FORCEPROP 2 LAST CDS_LIB standard
J 0
(-6575 2250);
DISPLAY INVISIBLE (-6575 2250);
FORCEADD OFFPAGE..5
(-6575 2150);
FORCEPROP 2 LAST $XR0 104 
J 0
(-6830 2150);
DISPLAY 0.638298 (-6830 2150);
PAINT MONO (-6830 2150);
FORCEPROP 2 LAST PATH I313
J 0
(-6825 2200);
DISPLAY 1.021277 (-6825 2200);
DISPLAY INVISIBLE (-6825 2200);
FORCEPROP 1 LAST COMMENT_BODY TRUE
J 0
(-6475 2075);
DISPLAY 0.872340 (-6475 2075);
PAINT GREEN (-6475 2075);
DISPLAY INVISIBLE (-6475 2075);
FORCEPROP 1 LAST OFFPAGE TRUE
J 0
(-6250 2025);
DISPLAY 0.872340 (-6250 2025);
PAINT GREEN (-6250 2025);
DISPLAY INVISIBLE (-6250 2025);
FORCEPROP 2 LAST CDS_LIB standard
J 0
(-6575 2150);
DISPLAY INVISIBLE (-6575 2150);
FORCEADD Q_RES..1
(-6650 2050);
FORCEPROP 1 LAST LOCATION R507
J 0
(-6975 2050);
DISPLAY 0.489362 (-6975 2050);
PAINT SKYBLUE (-6975 2050);
FORCEPROP 0 LAST $SEC 1
J 0
(-6825 2100);
DISPLAY 0.680851 (-6825 2100);
PAINT MONO (-6825 2100);
DISPLAY INVISIBLE (-6825 2100);
FORCEPROP 0 LAST CDS_SEC 1
J 0
(-6825 2100);
DISPLAY 1.021277 (-6825 2100);
DISPLAY INVISIBLE (-6825 2100);
FORCEPROP 1 LASTPIN (-6750 2050) $PN 1
J 0
(-6738 2062);
DISPLAY 0.489362 (-6738 2062);
PAINT MONO (-6738 2062);
FORCEPROP 1 LASTPIN (-6550 2050) $PN 2
J 0
(-6588 2062);
DISPLAY 0.489362 (-6588 2062);
PAINT MONO (-6588 2062);
FORCEPROP 1 LAST TOLERANCE 1%
J 0
(-6375 2050);
DISPLAY 0.489362 (-6375 2050);
PAINT SKYBLUE (-6375 2050);
FORCEPROP 1 LAST VALUE 15   
J 2
(-6325 2050);
DISPLAY 0.489362 (-6325 2050);
PAINT SKYBLUE (-6325 2050);
FORCEPROP 1 LAST PART_NUMBER CS01502FB11
J 0
(-6525 2025);
DISPLAY 0.489362 (-6525 2025);
PAINT SKYBLUE (-6525 2025);
FORCEPROP 1 LAST PACK_TYPE 0402LF
J 0
(-6975 2025);
DISPLAY 0.489362 (-6975 2025);
PAINT SKYBLUE (-6975 2025);
FORCEPROP 2 LAST CDS_LIB pure_quanta
J 0
(-6650 2050);
DISPLAY INVISIBLE (-6650 2050);
FORCEPROP 1 LAST PATH I314
J 0
(-6700 2200);
DISPLAY 0.978723 (-6700 2200);
PAINT WHITE (-6700 2200);
DISPLAY INVISIBLE (-6700 2200);
FORCEPROP 1 LAST WATTAGE 1/16W
J 2
(-6425 2175);
DISPLAY 0.638298 (-6425 2175);
PAINT SKYBLUE (-6425 2175);
DISPLAY INVISIBLE (-6425 2175);
FORCEPROP 1 LAST MATERIAL CHIP
J 0
(-6775 2175);
DISPLAY 0.638298 (-6775 2175);
PAINT SKYBLUE (-6775 2175);
DISPLAY INVISIBLE (-6775 2175);
FORCEADD OFFPAGE..5
(-6575 1950);
FORCEPROP 2 LAST $XR0 104 
J 0
(-6830 1950);
DISPLAY 0.638298 (-6830 1950);
PAINT MONO (-6830 1950);
FORCEPROP 2 LAST PATH I315
J 0
(-6825 2000);
DISPLAY 1.021277 (-6825 2000);
DISPLAY INVISIBLE (-6825 2000);
FORCEPROP 1 LAST COMMENT_BODY TRUE
J 0
(-6475 1875);
DISPLAY 0.872340 (-6475 1875);
PAINT GREEN (-6475 1875);
DISPLAY INVISIBLE (-6475 1875);
FORCEPROP 1 LAST OFFPAGE TRUE
J 0
(-6250 1825);
DISPLAY 0.872340 (-6250 1825);
PAINT GREEN (-6250 1825);
DISPLAY INVISIBLE (-6250 1825);
FORCEPROP 2 LAST CDS_LIB standard
J 0
(-6575 1950);
DISPLAY INVISIBLE (-6575 1950);
FORCEADD OFFPAGE..1
(-7525 2050);
FORCEPROP 2 LAST $XR0 104 
J 0
(-7777 2050);
DISPLAY 0.638298 (-7777 2050);
PAINT MONO (-7777 2050);
FORCEPROP 2 LAST PATH I316
J 0
(-7775 2100);
DISPLAY 1.021277 (-7775 2100);
DISPLAY INVISIBLE (-7775 2100);
FORCEPROP 1 LAST COMMENT_BODY TRUE
J 0
(-7400 1950);
DISPLAY 0.872340 (-7400 1950);
PAINT GREEN (-7400 1950);
DISPLAY INVISIBLE (-7400 1950);
FORCEPROP 1 LAST OFFPAGE TRUE
J 0
(-7200 1925);
DISPLAY 0.872340 (-7200 1925);
PAINT GREEN (-7200 1925);
DISPLAY INVISIBLE (-7200 1925);
FORCEPROP 2 LAST CDS_LIB mstr_standard
J 0
(-7525 2050);
DISPLAY INVISIBLE (-7525 2050);
FORCEADD CAD_NOTE..1
(-7725 2325);
FORCEPROP 0 LAST L1 R1985 PLACE CLOSE TO CPU < 25MM
J 0
(-7875 2200);
DISPLAY 0.617021 (-7875 2200);
PAINT WHITE (-7875 2200);
FORCEPROP 2 LAST CDS_LIB pure_quanta_power
J 0
(-7725 2325);
DISPLAY INVISIBLE (-7725 2325);
FORCEPROP 1 LAST COMMENT_BODY TRUE
J 0
(-7700 2425);
DISPLAY 0.574468 (-7700 2425);
PAINT WHITE (-7700 2425);
DISPLAY INVISIBLE (-7700 2425);
FORCEADD QUANTA_TITLE_BLOCK_C..1
(0 0);
FORCEPROP 0 LAST CDS_CON_LAST_MODIFIED Fri Mar 11 14:52:32 2022
J 0
(-1885 15);
DISPLAY INVISIBLE (-1885 15);
FORCEPROP 1 LAST CUSTOM_TXT_CDS <CON_LAST_MODIFIED>
J 0
(-1885 15);
DISPLAY 0.978723 (-1885 15);
FORCEPROP 2 LAST CUSTOM_TXT_CDS <XR_PAGE_TITLE>
J 0
(-7890 5250);
DISPLAY 0.638298 (-7890 5250);
PAINT PINK (-7890 5250);
DISPLAY INVISIBLE (-7890 5250);
FORCEPROP 1 LAST CUSTOM_TXT_CDS <NAME_2>
J 0
(-3175 50);
FORCEPROP 1 LAST CUSTOM_TXT_CDS <NAME_1>
J 0
(-3175 175);
FORCEPROP 1 LAST CUSTOM_TXT_CDS <Q_NUMBER>
J 0
(-1403 103);
DISPLAY 1.212766 (-1403 103);
FORCEPROP 1 LAST CUSTOM_TXT_CDS <Q_PROJ>
J 0
(-2382 102);
DISPLAY 1.212766 (-2382 102);
FORCEPROP 1 LAST CUSTOM_TXT_CDS <Q_REV>
J 0
(-184 103);
DISPLAY 1.212766 (-184 103);
FORCEPROP 1 LAST CUSTOM_TXT_CDS <CON_PAGE_NUM> OF <CON_TOTAL_PAGES>
J 0
(-446 18);
DISPLAY 0.978723 (-446 18);
FORCEPROP 1 LAST Q_TITLE CPU1 DDR CHH
J 0
(-9366 26);
DISPLAY 2.446809 (-9366 26);
PAINT GREEN (-9366 26);
FORCEPROP 1 LAST Q_DEPT BU9
J 1
(-3763 49);
DISPLAY 1.957447 (-3763 49);
PAINT GREEN (-3763 49);
FORCEPROP 2 LAST PAGE_BORDER TRUE
J 0
(-7890 5250);
DISPLAY 0.638298 (-7890 5250);
PAINT PINK (-7890 5250);
DISPLAY INVISIBLE (-7890 5250);
FORCEPROP 2 LAST CDS_LIB pure_quanta
J 0
(0 0);
DISPLAY INVISIBLE (0 0);
FORCEPROP 1 LAST CDS_LMAN_SYM_OUTLINE -9475,6775,100,-125
J 0
(0 0);
DISPLAY 0.468085 (0 0);
PAINT GREEN (0 0);
DISPLAY INVISIBLE (0 0);
FORCEPROP 1 LAST COMMENT_BODY TRUE
J 0
(12 -13);
DISPLAY 0.978723 (12 -13);
PAINT GREEN (12 -13);
DISPLAY INVISIBLE (12 -13);
FORCEPROP 2 LAST CDS_XR_PAGE_TITLE CR-44 : @T6G_MB_LIB.T6G(SCH_1):PAGE44
J 0
(-7890 5250);
DISPLAY 0.638298 (-7890 5250);
PAINT PINK (-7890 5250);
DISPLAY INVISIBLE (-7890 5250);
WIRE 17 -1 (-3300 5925)(-3300 5875);
WIRE 17 -1 (-3300 5925)(-2675 5925);
FORCEPROP 2 LAST SIG_NAME M_H_CPU1_SA_DQ<31:0>
J 2
(-2735 5935);
DISPLAY 0.489362 (-2735 5935);
WIRE 17 -1 (-3300 5875)(-3300 5825);
WIRE 17 -1 (-3300 5825)(-3300 5775);
WIRE 17 -1 (-3300 5775)(-3300 5725);
WIRE 17 -1 (-3300 5725)(-3300 5675);
WIRE 17 -1 (-3300 5675)(-3300 5625);
WIRE 17 -1 (-3300 5625)(-3300 5575);
WIRE 17 -1 (-3300 5575)(-3300 5475);
WIRE 17 -1 (-3300 5475)(-3300 5425);
WIRE 17 -1 (-3300 5425)(-3300 5375);
WIRE 17 -1 (-3300 5375)(-3300 5325);
WIRE 17 -1 (-3300 5325)(-3300 5275);
WIRE 17 -1 (-3300 5275)(-3300 5225);
WIRE 17 -1 (-3300 5225)(-3300 5175);
WIRE 17 -1 (-3300 5175)(-3300 5125);
WIRE 17 -1 (-3300 5025)(-3300 5125);
WIRE 17 -1 (-3300 4975)(-3300 5025);
WIRE 17 -1 (-3300 4925)(-3300 4975);
WIRE 17 -1 (-3300 4875)(-3300 4925);
WIRE 17 -1 (-3300 4875)(-3300 4825);
WIRE 17 -1 (-3300 4825)(-3300 4775);
WIRE 17 -1 (-3300 4775)(-3300 4725);
WIRE 17 -1 (-3300 4725)(-3300 4675);
WIRE 17 -1 (-3300 4675)(-3300 4575);
WIRE 17 -1 (-3300 4575)(-3300 4525);
WIRE 17 -1 (-3300 4525)(-3300 4475);
WIRE 17 -1 (-3300 4475)(-3300 4425);
WIRE 17 -1 (-3300 4375)(-3300 4425);
WIRE 17 -1 (-3300 4325)(-3300 4375);
WIRE 17 -1 (-3300 4275)(-3300 4325);
WIRE 17 -1 (-3300 4225)(-3300 4275);
WIRE 17 -1 (-3300 4125)(-2675 4125);
FORCEPROP 2 LAST SIG_NAME M_H_CPU1_SB_DQ<31:0>
J 2
(-2735 4135);
DISPLAY 0.489362 (-2735 4135);
WIRE 17 -1 (-3300 3575)(-3300 3525);
WIRE 17 -1 (-3300 3625)(-3300 3575);
WIRE 17 -1 (-3300 3525)(-3300 3475);
WIRE 17 -1 (-3300 3475)(-3300 3425);
WIRE 17 -1 (-3300 3675)(-3300 3625);
WIRE 17 -1 (-3300 3775)(-3300 3675);
WIRE 17 -1 (-3300 3425)(-3300 3375);
WIRE 17 -1 (-3300 3375)(-3300 3325);
WIRE 17 -1 (-3300 3825)(-3300 3775);
WIRE 17 -1 (-3300 3875)(-3300 3825);
WIRE 17 -1 (-3300 3225)(-3300 3325);
WIRE 17 -1 (-3300 3175)(-3300 3225);
WIRE 17 -1 (-3300 3925)(-3300 3875);
WIRE 17 -1 (-3300 3975)(-3300 3925);
WIRE 17 -1 (-3300 3125)(-3300 3175);
WIRE 17 -1 (-3300 3075)(-3300 3125);
WIRE 17 -1 (-3300 4025)(-3300 3975);
WIRE 17 -1 (-3300 4075)(-3300 4025);
WIRE 17 -1 (-3300 3075)(-3300 3025);
WIRE 17 -1 (-3300 3025)(-3300 2975);
WIRE 17 -1 (-3300 4125)(-3300 4075);
WIRE 17 -1 (-3300 2975)(-3300 2925);
WIRE 17 -1 (-3300 2925)(-3300 2875);
WIRE 17 -1 (-3300 2875)(-3300 2775);
WIRE 17 -1 (-3300 2775)(-3300 2725);
WIRE 17 -1 (-3300 2725)(-3300 2675);
WIRE 17 -1 (-3300 2675)(-3300 2625);
WIRE 17 -1 (-3300 2575)(-3300 2625);
WIRE 17 -1 (-3300 2525)(-3300 2575);
WIRE 17 -1 (-3300 2475)(-3300 2525);
WIRE 17 -1 (-3300 2425)(-3300 2475);
WIRE 17 -1 (-3300 2325)(-3300 2275);
WIRE 17 -1 (-3300 2325)(-3300 2350);
WIRE 17 -1 (-3300 2225)(-3300 2275);
WIRE 17 -1 (-3300 2225)(-3300 2175);
WIRE 17 -1 (-3300 2350)(-2800 2350);
FORCEPROP 2 LAST SIG_NAME M_H_CPU1_SA_CB<7:0>
J 2
(-2800 2360);
DISPLAY 0.489362 (-2800 2360);
WIRE 17 -1 (-3300 2125)(-3300 2175);
WIRE 17 -1 (-3300 2075)(-3300 2125);
WIRE 17 -1 (-3300 2025)(-3300 2075);
WIRE 17 -1 (-3300 1975)(-3300 2025);
WIRE 17 -1 (-3300 1875)(-3300 1900);
WIRE 17 -1 (-3300 1875)(-3300 1825);
WIRE 17 -1 (-3300 1900)(-2800 1900);
FORCEPROP 2 LAST SIG_NAME M_H_CPU1_SB_CB<7:0>
J 2
(-2800 1910);
DISPLAY 0.489362 (-2800 1910);
WIRE 17 -1 (-3300 1775)(-3300 1825);
WIRE 17 -1 (-3300 1775)(-3300 1725);
WIRE 17 -1 (-3300 1675)(-3300 1725);
WIRE 17 -1 (-3300 1625)(-3300 1675);
WIRE 17 -1 (-3300 1575)(-3300 1625);
WIRE 17 -1 (-3300 1525)(-3300 1575);
WIRE 17 -1 (-6025 5675)(-6025 5575);
WIRE 17 -1 (-6025 5775)(-6025 5675);
WIRE 17 -1 (-6025 5575)(-6025 5475);
WIRE 17 -1 (-6025 5375)(-6025 5475);
WIRE 17 -1 (-6025 5875)(-6025 5775);
FORCEPROP 2 LAST SIG_NAME M_H_CPU1_SA_DQS_DN<9:0>
J 2
(-6060 5885);
DISPLAY 0.489362 (-6060 5885);
WIRE 17 -1 (-6025 5275)(-6025 5375);
WIRE 17 -1 (-6025 5175)(-6025 5275);
WIRE 17 -1 (-6025 5175)(-6025 5075);
WIRE 17 -1 (-5825 5925)(-5825 5825);
WIRE 17 -1 (-5825 5925)(-6625 5925);
FORCEPROP 2 LAST SIG_NAME M_H_CPU1_SA_DQS_DP<9:0>
J 2
(-6060 5935);
DISPLAY 0.489362 (-6060 5935);
WIRE 17 -1 (-6025 5075)(-6025 4975);
WIRE 17 -1 (-5825 5825)(-5825 5725);
WIRE 17 -1 (-5825 5725)(-5825 5625);
WIRE 17 -1 (-5825 5625)(-5825 5525);
WIRE 17 -1 (-5825 5425)(-5825 5525);
WIRE 17 -1 (-5825 5325)(-5825 5425);
WIRE 17 -1 (-5825 5225)(-5825 5325);
WIRE 17 -1 (-5825 5225)(-5825 5125);
WIRE 17 -1 (-5825 5125)(-5825 5025);
WIRE 17 -1 (-6025 4825)(-6025 4725);
FORCEPROP 2 LAST SIG_NAME M_H_CPU1_SB_DQS_DN<9:0>
J 2
(-6060 4835);
DISPLAY 0.489362 (-6060 4835);
WIRE 17 -1 (-6025 4625)(-6025 4525);
WIRE 17 -1 (-6025 4725)(-6025 4625);
WIRE 17 -1 (-6025 4525)(-6025 4425);
WIRE 17 -1 (-6025 4325)(-6025 4425);
WIRE 17 -1 (-6025 4225)(-6025 4325);
WIRE 17 -1 (-6025 4125)(-6025 4225);
WIRE 17 -1 (-6025 4125)(-6025 4025);
WIRE 17 -1 (-5825 4875)(-5825 4775);
WIRE 17 -1 (-5825 4875)(-6625 4875);
FORCEPROP 2 LAST SIG_NAME M_H_CPU1_SB_DQS_DP<9:0>
J 2
(-6060 4885);
DISPLAY 0.489362 (-6060 4885);
WIRE 17 -1 (-6025 4025)(-6025 3925);
WIRE 17 -1 (-5825 4775)(-5825 4675);
WIRE 17 -1 (-5825 4675)(-5825 4575);
WIRE 17 -1 (-5825 4575)(-5825 4475);
WIRE 17 -1 (-5825 4375)(-5825 4475);
WIRE 17 -1 (-5825 4275)(-5825 4375);
WIRE 17 -1 (-5825 4175)(-5825 4275);
WIRE 17 -1 (-5825 4175)(-5825 4075);
WIRE 17 -1 (-5825 4075)(-5825 3975);
WIRE 17 -1 (-6025 3725)(-6025 3775);
WIRE 17 -1 (-6025 3675)(-6025 3725);
WIRE 17 -1 (-6025 3775)(-6525 3775);
FORCEPROP 2 LAST SIG_NAME M_H_CPU1_SA_CA<6:0>
J 0
(-6525 3785);
DISPLAY 0.489362 (-6525 3785);
WIRE 17 -1 (-6025 3325)(-6025 3375);
WIRE 17 -1 (-6025 3275)(-6025 3325);
WIRE 17 -1 (-6025 3375)(-6525 3375);
FORCEPROP 2 LAST SIG_NAME M_H_CPU1_SB_CA<6:0>
J 0
(-6525 3385);
DISPLAY 0.489362 (-6525 3385);
WIRE 17 -1 (-6025 3625)(-6025 3675);
WIRE 17 -1 (-6025 3225)(-6025 3275);
WIRE 17 -1 (-6025 3575)(-6025 3625);
WIRE 17 -1 (-6025 3525)(-6025 3575);
WIRE 17 -1 (-6025 3475)(-6025 3525);
WIRE 17 -1 (-6025 3175)(-6025 3225);
WIRE 17 -1 (-6025 3125)(-6025 3175);
WIRE 17 -1 (-6025 3075)(-6025 3125);
WIRE 17 -1 (-6025 5875)(-6625 5875);
WIRE 17 -1 (-6025 4825)(-6625 4825);
WIRE 16 -1 (-7475 2050)(-6750 2050);
FORCEPROP 2 LAST SIG_NAME M_H_CPU1_ALERT_N
J 0
(-7435 2060);
DISPLAY 0.489362 (-7435 2060);
WIRE 16 -1 (-6525 1100)(-5425 1100);
FORCEPROP 2 LAST SIG_NAME TP_M_H_CPU1_SA_TEST39H
J 0
(-6510 1110);
DISPLAY 0.489362 (-6510 1110);
FORCEPROP 2 LASTPROP $XRERR UNIQUE?
J 0
(-6765 1100);
DISPLAY 0.638298 (-6765 1100);
PAINT MONO (-6765 1100);
DISPLAY INVISIBLE (-6765 1100);
WIRE 16 -1 (-6550 2050)(-5425 2050);
FORCEPROP 2 LAST SIG_NAME M_H_CPU1_ALERT_R_N
J 0
(-6260 2060);
DISPLAY 0.489362 (-6260 2060);
FORCEPROP 2 LASTPROP $XRERR UNIQUE?
J 0
(-6500 2060);
DISPLAY 0.638298 (-6500 2060);
PAINT MONO (-6500 2060);
DISPLAY INVISIBLE (-6500 2060);
WIRE 16 -1 (-6525 2850)(-5425 2850);
FORCEPROP 2 LAST SIG_NAME M_H_CPU1_CLK_DN<0>
J 0
(-6525 2860);
DISPLAY 0.489362 (-6525 2860);
WIRE 16 -1 (-6525 2900)(-5425 2900);
FORCEPROP 2 LAST SIG_NAME M_H_CPU1_CLK_DP<0>
J 0
(-6525 2910);
DISPLAY 0.489362 (-6525 2910);
WIRE 16 -1 (-6525 2750)(-5425 2750);
FORCEPROP 2 LAST SIG_NAME M_H_CPU1_SA_CS_N<0>
J 0
(-6525 2760);
DISPLAY 0.489362 (-6525 2760);
WIRE 16 -1 (-6525 2700)(-5425 2700);
FORCEPROP 2 LAST SIG_NAME M_H_CPU1_SA_CS_N<1>
J 0
(-6525 2710);
DISPLAY 0.489362 (-6525 2710);
WIRE 16 -1 (-6525 2600)(-5425 2600);
FORCEPROP 2 LAST SIG_NAME M_H_CPU1_SA_RSP<0>
J 0
(-6525 2610);
DISPLAY 0.489362 (-6525 2610);
WIRE 16 -1 (-6525 2500)(-5425 2500);
FORCEPROP 2 LAST SIG_NAME M_H_CPU1_SA_PAR
J 0
(-6525 2510);
DISPLAY 0.489362 (-6525 2510);
WIRE 16 -1 (-6525 2350)(-5425 2350);
FORCEPROP 2 LAST SIG_NAME M_H_CPU1_SB_CS_N<1>
J 0
(-6525 2360);
DISPLAY 0.489362 (-6525 2360);
WIRE 16 -1 (-6525 2400)(-5425 2400);
FORCEPROP 2 LAST SIG_NAME M_H_CPU1_SB_CS_N<0>
J 0
(-6525 2410);
DISPLAY 0.489362 (-6525 2410);
WIRE 16 -1 (-6525 2250)(-5425 2250);
FORCEPROP 2 LAST SIG_NAME M_H_CPU1_SB_RSP<0>
J 0
(-6525 2260);
DISPLAY 0.489362 (-6525 2260);
WIRE 16 -1 (-6525 2150)(-5425 2150);
FORCEPROP 2 LAST SIG_NAME M_H_CPU1_SB_PAR
J 0
(-6525 2160);
DISPLAY 0.489362 (-6525 2160);
WIRE 16 -1 (-6525 1950)(-5425 1950);
FORCEPROP 2 LAST SIG_NAME M_H_CPU1_RESET_N
J 0
(-6525 1960);
DISPLAY 0.489362 (-6525 1960);
WIRE 16 -1 (-5925 3050)(-5425 3050);
WIRE 16 -1 (-5725 3950)(-5425 3950);
WIRE 16 -1 (-5725 4050)(-5425 4050);
WIRE 16 -1 (-5925 3900)(-5425 3900);
WIRE 16 -1 (-5925 4000)(-5425 4000);
WIRE 16 -1 (-5925 3450)(-5425 3450);
WIRE 16 -1 (-5925 3100)(-5425 3100);
WIRE 16 -1 (-5925 3500)(-5425 3500);
WIRE 16 -1 (-5925 3150)(-5425 3150);
WIRE 16 -1 (-5925 3550)(-5425 3550);
WIRE 16 -1 (-5925 3200)(-5425 3200);
WIRE 16 -1 (-5925 3600)(-5425 3600);
WIRE 16 -1 (-5925 3250)(-5425 3250);
WIRE 16 -1 (-5925 3650)(-5425 3650);
WIRE 16 -1 (-5925 3300)(-5425 3300);
WIRE 16 -1 (-5925 3700)(-5425 3700);
WIRE 16 -1 (-5925 3350)(-5425 3350);
WIRE 16 -1 (-5925 3750)(-5425 3750);
WIRE 16 -1 (-5725 4150)(-5425 4150);
WIRE 16 -1 (-5725 4250)(-5425 4250);
WIRE 16 -1 (-5725 4350)(-5425 4350);
WIRE 16 -1 (-5725 4450)(-5425 4450);
WIRE 16 -1 (-5725 5000)(-5425 5000);
WIRE 16 -1 (-5725 4550)(-5425 4550);
WIRE 16 -1 (-5925 4100)(-5425 4100);
WIRE 16 -1 (-5725 5100)(-5425 5100);
WIRE 16 -1 (-5725 4650)(-5425 4650);
WIRE 16 -1 (-5925 4200)(-5425 4200);
WIRE 16 -1 (-5725 4750)(-5425 4750);
WIRE 16 -1 (-5925 4300)(-5425 4300);
WIRE 16 -1 (-5725 4850)(-5425 4850);
WIRE 16 -1 (-5925 4400)(-5425 4400);
WIRE 16 -1 (-5925 4950)(-5425 4950);
WIRE 16 -1 (-5925 4500)(-5425 4500);
WIRE 16 -1 (-5925 5050)(-5425 5050);
WIRE 16 -1 (-5925 4600)(-5425 4600);
WIRE 16 -1 (-5925 4700)(-5425 4700);
WIRE 16 -1 (-5925 4800)(-5425 4800);
WIRE 16 -1 (-5925 5750)(-5425 5750);
WIRE 16 -1 (-5925 5850)(-5425 5850);
WIRE 16 -1 (-5725 5200)(-5425 5200);
WIRE 16 -1 (-5725 5300)(-5425 5300);
WIRE 16 -1 (-5725 5400)(-5425 5400);
WIRE 16 -1 (-5725 5500)(-5425 5500);
WIRE 16 -1 (-5725 5600)(-5425 5600);
WIRE 16 -1 (-5925 5150)(-5425 5150);
WIRE 16 -1 (-5725 5700)(-5425 5700);
WIRE 16 -1 (-5925 5250)(-5425 5250);
WIRE 16 -1 (-5725 5800)(-5425 5800);
WIRE 16 -1 (-5925 5350)(-5425 5350);
WIRE 16 -1 (-5725 5900)(-5425 5900);
WIRE 16 -1 (-5925 5450)(-5425 5450);
WIRE 16 -1 (-5925 5550)(-5425 5550);
WIRE 16 -1 (-5925 5650)(-5425 5650);
WIRE 16 -1 (-3825 1500)(-3400 1500);
WIRE 16 -1 (-3825 1550)(-3400 1550);
WIRE 16 -1 (-3825 1600)(-3400 1600);
WIRE 16 -1 (-3825 1650)(-3400 1650);
WIRE 16 -1 (-3825 1700)(-3400 1700);
WIRE 16 -1 (-3825 1750)(-3400 1750);
WIRE 16 -1 (-3825 1950)(-3400 1950);
WIRE 16 -1 (-3825 1800)(-3400 1800);
WIRE 16 -1 (-3825 2000)(-3400 2000);
WIRE 16 -1 (-3825 1850)(-3400 1850);
WIRE 16 -1 (-3825 2050)(-3400 2050);
WIRE 16 -1 (-3825 2450)(-3400 2450);
WIRE 16 -1 (-3825 2100)(-3400 2100);
WIRE 16 -1 (-3825 2150)(-3400 2150);
WIRE 16 -1 (-3825 2200)(-3400 2200);
WIRE 16 -1 (-3825 2250)(-3400 2250);
WIRE 16 -1 (-3825 2300)(-3400 2300);
WIRE 16 -1 (-3825 3050)(-3400 3050);
WIRE 16 -1 (-3825 2500)(-3400 2500);
WIRE 16 -1 (-3825 2550)(-3400 2550);
WIRE 16 -1 (-3825 2600)(-3400 2600);
WIRE 16 -1 (-3825 2650)(-3400 2650);
WIRE 16 -1 (-3825 2700)(-3400 2700);
WIRE 16 -1 (-3825 2750)(-3400 2750);
WIRE 16 -1 (-3825 2850)(-3400 2850);
WIRE 16 -1 (-3825 2900)(-3400 2900);
WIRE 16 -1 (-3825 2950)(-3400 2950);
WIRE 16 -1 (-3825 3000)(-3400 3000);
WIRE 16 -1 (-3825 2400)(-3400 2400);
WIRE 16 -1 (-3825 3600)(-3400 3600);
WIRE 16 -1 (-3825 3650)(-3400 3650);
WIRE 16 -1 (-3825 3750)(-3400 3750);
WIRE 16 -1 (-3825 3800)(-3400 3800);
WIRE 16 -1 (-3825 3850)(-3400 3850);
WIRE 16 -1 (-3825 3900)(-3400 3900);
WIRE 16 -1 (-3825 3100)(-3400 3100);
WIRE 16 -1 (-3825 3950)(-3400 3950);
WIRE 16 -1 (-3825 3150)(-3400 3150);
WIRE 16 -1 (-3825 4000)(-3400 4000);
WIRE 16 -1 (-3825 3200)(-3400 3200);
WIRE 16 -1 (-3825 4050)(-3400 4050);
WIRE 16 -1 (-3825 3300)(-3400 3300);
WIRE 16 -1 (-3825 3350)(-3400 3350);
WIRE 16 -1 (-3825 3400)(-3400 3400);
WIRE 16 -1 (-3825 3450)(-3400 3450);
WIRE 16 -1 (-3825 3500)(-3400 3500);
WIRE 16 -1 (-3825 3550)(-3400 3550);
WIRE 16 -1 (-3825 4500)(-3400 4500);
WIRE 16 -1 (-3825 4550)(-3400 4550);
WIRE 16 -1 (-3825 4650)(-3400 4650);
WIRE 16 -1 (-3825 4700)(-3400 4700);
WIRE 16 -1 (-3825 4750)(-3400 4750);
WIRE 16 -1 (-3825 4800)(-3400 4800);
WIRE 16 -1 (-3825 4200)(-3400 4200);
WIRE 16 -1 (-3825 4250)(-3400 4250);
WIRE 16 -1 (-3825 4100)(-3400 4100);
WIRE 16 -1 (-3825 4850)(-3400 4850);
WIRE 16 -1 (-3825 4900)(-3400 4900);
WIRE 16 -1 (-3825 4300)(-3400 4300);
WIRE 16 -1 (-3825 4950)(-3400 4950);
WIRE 16 -1 (-3825 4350)(-3400 4350);
WIRE 16 -1 (-3825 5000)(-3400 5000);
WIRE 16 -1 (-3825 4400)(-3400 4400);
WIRE 16 -1 (-3825 5100)(-3400 5100);
WIRE 16 -1 (-3825 4450)(-3400 4450);
WIRE 16 -1 (-3825 5150)(-3400 5150);
WIRE 16 -1 (-3825 5200)(-3400 5200);
WIRE 16 -1 (-3825 5400)(-3400 5400);
WIRE 16 -1 (-3825 5250)(-3400 5250);
WIRE 16 -1 (-3825 5450)(-3400 5450);
WIRE 16 -1 (-3825 5300)(-3400 5300);
WIRE 16 -1 (-3825 5550)(-3400 5550);
WIRE 16 -1 (-3825 5350)(-3400 5350);
WIRE 16 -1 (-3825 5600)(-3400 5600);
WIRE 16 -1 (-3825 5650)(-3400 5650);
WIRE 16 -1 (-3825 5700)(-3400 5700);
WIRE 16 -1 (-3825 5750)(-3400 5750);
WIRE 16 -1 (-3825 5800)(-3400 5800);
WIRE 16 -1 (-3825 5850)(-3400 5850);
WIRE 16 -1 (-3825 5900)(-3400 5900);
QUIT
